(kicad_sch
	(version 20250114)
	(generator "eeschema")
	(generator_version "9.0")
	(paper "A3")
	(title_block
		(title "LPDDR4 testbed")
		(date "2024-03-26")
		(rev "1.2.2")
	)
	(text "LPDDR4"
		(exclude_from_sim no)
		(at 27.305 26.035 0)
		(effects
			(font
				(size 2.4892 2.4892)
				(thickness 0.4978)
				(bold yes)
			)
			(justify left bottom)
		)
	)
	(junction
		(at 149.225 76.2)
		(diameter 0)
		(color 0 0 0 0)
	)
	(junction
		(at 142.24 45.72)
		(diameter 0)
		(color 0 0 0 0)
	)
	(junction
		(at 128.27 176.53)
		(diameter 0)
		(color 0 0 0 0)
	)
	(junction
		(at 135.255 45.72)
		(diameter 0)
		(color 0 0 0 0)
	)
	(junction
		(at 121.285 146.05)
		(diameter 0)
		(color 0 0 0 0)
	)
	(junction
		(at 128.27 45.72)
		(diameter 0)
		(color 0 0 0 0)
	)
	(junction
		(at 114.3 146.05)
		(diameter 0)
		(color 0 0 0 0)
	)
	(junction
		(at 156.21 76.2)
		(diameter 0)
		(color 0 0 0 0)
	)
	(junction
		(at 128.27 60.96)
		(diameter 0)
		(color 0 0 0 0)
	)
	(junction
		(at 114.3 161.29)
		(diameter 0)
		(color 0 0 0 0)
	)
	(junction
		(at 163.195 76.2)
		(diameter 0)
		(color 0 0 0 0)
	)
	(junction
		(at 187.96 61.595)
		(diameter 0)
		(color 0 0 0 0)
	)
	(junction
		(at 121.285 76.2)
		(diameter 0)
		(color 0 0 0 0)
	)
	(junction
		(at 128.27 146.05)
		(diameter 0)
		(color 0 0 0 0)
	)
	(junction
		(at 114.3 60.96)
		(diameter 0)
		(color 0 0 0 0)
	)
	(junction
		(at 121.285 176.53)
		(diameter 0)
		(color 0 0 0 0)
	)
	(junction
		(at 135.255 76.2)
		(diameter 0)
		(color 0 0 0 0)
	)
	(junction
		(at 174.625 116.84)
		(diameter 0)
		(color 0 0 0 0)
	)
	(junction
		(at 142.24 176.53)
		(diameter 0)
		(color 0 0 0 0)
	)
	(junction
		(at 142.24 76.2)
		(diameter 0)
		(color 0 0 0 0)
	)
	(junction
		(at 135.255 146.05)
		(diameter 0)
		(color 0 0 0 0)
	)
	(junction
		(at 156.21 45.72)
		(diameter 0)
		(color 0 0 0 0)
	)
	(junction
		(at 156.21 146.05)
		(diameter 0)
		(color 0 0 0 0)
	)
	(junction
		(at 135.255 176.53)
		(diameter 0)
		(color 0 0 0 0)
	)
	(junction
		(at 114.3 176.53)
		(diameter 0)
		(color 0 0 0 0)
	)
	(junction
		(at 187.96 68.58)
		(diameter 0)
		(color 0 0 0 0)
	)
	(junction
		(at 121.285 161.29)
		(diameter 0)
		(color 0 0 0 0)
	)
	(junction
		(at 142.24 146.05)
		(diameter 0)
		(color 0 0 0 0)
	)
	(junction
		(at 163.195 176.53)
		(diameter 0)
		(color 0 0 0 0)
	)
	(junction
		(at 149.225 176.53)
		(diameter 0)
		(color 0 0 0 0)
	)
	(junction
		(at 149.225 146.05)
		(diameter 0)
		(color 0 0 0 0)
	)
	(junction
		(at 114.3 76.2)
		(diameter 0)
		(color 0 0 0 0)
	)
	(junction
		(at 156.21 176.53)
		(diameter 0)
		(color 0 0 0 0)
	)
	(junction
		(at 121.285 60.96)
		(diameter 0)
		(color 0 0 0 0)
	)
	(junction
		(at 189.23 186.69)
		(diameter 0)
		(color 0 0 0 0)
	)
	(junction
		(at 121.285 45.72)
		(diameter 0)
		(color 0 0 0 0)
	)
	(junction
		(at 149.225 45.72)
		(diameter 0)
		(color 0 0 0 0)
	)
	(junction
		(at 114.3 45.72)
		(diameter 0)
		(color 0 0 0 0)
	)
	(junction
		(at 128.27 76.2)
		(diameter 0)
		(color 0 0 0 0)
	)
	(no_connect
		(at 238.76 171.45)
	)
	(no_connect
		(at 238.76 186.69)
	)
	(no_connect
		(at 198.12 201.93)
	)
	(no_connect
		(at 198.12 209.55)
	)
	(no_connect
		(at 238.76 219.71)
	)
	(no_connect
		(at 238.76 212.09)
	)
	(no_connect
		(at 238.76 224.79)
	)
	(no_connect
		(at 198.12 181.61)
	)
	(no_connect
		(at 238.76 184.15)
	)
	(no_connect
		(at 238.76 166.37)
	)
	(no_connect
		(at 238.76 179.07)
	)
	(no_connect
		(at 198.12 184.15)
	)
	(no_connect
		(at 198.12 196.85)
	)
	(no_connect
		(at 238.76 214.63)
	)
	(no_connect
		(at 238.76 189.23)
	)
	(no_connect
		(at 238.76 217.17)
	)
	(no_connect
		(at 238.76 176.53)
	)
	(no_connect
		(at 198.12 194.31)
	)
	(no_connect
		(at 238.76 201.93)
	)
	(no_connect
		(at 238.76 207.01)
	)
	(no_connect
		(at 238.76 209.55)
	)
	(no_connect
		(at 198.12 207.01)
	)
	(no_connect
		(at 238.76 181.61)
	)
	(no_connect
		(at 198.12 199.39)
	)
	(no_connect
		(at 198.12 204.47)
	)
	(no_connect
		(at 238.76 168.91)
	)
	(no_connect
		(at 238.76 204.47)
	)
	(no_connect
		(at 238.76 173.99)
	)
	(no_connect
		(at 238.76 199.39)
	)
	(no_connect
		(at 238.76 222.25)
	)
	(no_connect
		(at 238.76 191.77)
	)
	(wire
		(pts
			(xy 198.12 109.22) (xy 190.5 109.22)
		)
		(stroke
			(width 0)
			(type default)
		)
	)
	(wire
		(pts
			(xy 142.24 173.99) (xy 142.24 161.29)
		)
		(stroke
			(width 0)
			(type default)
		)
	)
	(wire
		(pts
			(xy 112.395 60.96) (xy 114.3 60.96)
		)
		(stroke
			(width 0)
			(type default)
		)
	)
	(wire
		(pts
			(xy 114.3 76.2) (xy 114.3 77.47)
		)
		(stroke
			(width 0)
			(type default)
		)
	)
	(wire
		(pts
			(xy 198.12 101.6) (xy 190.5 101.6)
		)
		(stroke
			(width 0)
			(type default)
		)
	)
	(wire
		(pts
			(xy 198.12 104.14) (xy 190.5 104.14)
		)
		(stroke
			(width 0)
			(type default)
		)
	)
	(wire
		(pts
			(xy 238.76 121.92) (xy 245.745 121.92)
		)
		(stroke
			(width 0)
			(type default)
		)
	)
	(wire
		(pts
			(xy 128.27 45.72) (xy 128.27 46.99)
		)
		(stroke
			(width 0)
			(type default)
		)
	)
	(wire
		(pts
			(xy 128.27 176.53) (xy 135.255 176.53)
		)
		(stroke
			(width 0)
			(type default)
		)
	)
	(wire
		(pts
			(xy 198.12 73.66) (xy 142.24 73.66)
		)
		(stroke
			(width 0)
			(type default)
		)
	)
	(wire
		(pts
			(xy 135.255 45.72) (xy 135.255 46.99)
		)
		(stroke
			(width 0)
			(type default)
		)
	)
	(wire
		(pts
			(xy 113.03 76.2) (xy 114.3 76.2)
		)
		(stroke
			(width 0)
			(type default)
		)
	)
	(wire
		(pts
			(xy 198.12 93.98) (xy 190.5 93.98)
		)
		(stroke
			(width 0)
			(type default)
		)
	)
	(wire
		(pts
			(xy 128.27 176.53) (xy 128.27 177.8)
		)
		(stroke
			(width 0)
			(type default)
		)
	)
	(wire
		(pts
			(xy 135.255 76.2) (xy 142.24 76.2)
		)
		(stroke
			(width 0)
			(type default)
		)
	)
	(wire
		(pts
			(xy 121.285 161.29) (xy 142.24 161.29)
		)
		(stroke
			(width 0)
			(type default)
		)
	)
	(wire
		(pts
			(xy 156.21 45.72) (xy 156.21 46.99)
		)
		(stroke
			(width 0)
			(type default)
		)
	)
	(wire
		(pts
			(xy 128.27 182.88) (xy 128.27 183.515)
		)
		(stroke
			(width 0)
			(type default)
		)
	)
	(wire
		(pts
			(xy 189.23 192.405) (xy 189.23 193.04)
		)
		(stroke
			(width 0)
			(type default)
		)
	)
	(wire
		(pts
			(xy 196.85 61.595) (xy 187.96 61.595)
		)
		(stroke
			(width 0)
			(type default)
		)
	)
	(wire
		(pts
			(xy 196.85 124.46) (xy 196.85 127)
		)
		(stroke
			(width 0)
			(type default)
		)
	)
	(wire
		(pts
			(xy 128.27 60.96) (xy 142.24 60.96)
		)
		(stroke
			(width 0)
			(type default)
		)
	)
	(wire
		(pts
			(xy 149.225 176.53) (xy 149.225 177.8)
		)
		(stroke
			(width 0)
			(type default)
		)
	)
	(wire
		(pts
			(xy 149.225 183.515) (xy 149.225 182.88)
		)
		(stroke
			(width 0)
			(type default)
		)
	)
	(wire
		(pts
			(xy 149.225 45.72) (xy 156.21 45.72)
		)
		(stroke
			(width 0)
			(type default)
		)
	)
	(wire
		(pts
			(xy 114.3 152.4) (xy 114.3 153.035)
		)
		(stroke
			(width 0)
			(type default)
		)
	)
	(wire
		(pts
			(xy 128.27 82.55) (xy 128.27 83.185)
		)
		(stroke
			(width 0)
			(type default)
		)
	)
	(wire
		(pts
			(xy 194.945 217.17) (xy 198.12 217.17)
		)
		(stroke
			(width 0)
			(type default)
		)
	)
	(wire
		(pts
			(xy 149.225 76.2) (xy 149.225 77.47)
		)
		(stroke
			(width 0)
			(type default)
		)
	)
	(wire
		(pts
			(xy 178.435 68.58) (xy 175.26 68.58)
		)
		(stroke
			(width 0)
			(type default)
		)
	)
	(wire
		(pts
			(xy 238.76 111.76) (xy 245.745 111.76)
		)
		(stroke
			(width 0)
			(type default)
		)
	)
	(wire
		(pts
			(xy 114.3 60.96) (xy 121.285 60.96)
		)
		(stroke
			(width 0)
			(type default)
		)
	)
	(wire
		(pts
			(xy 135.255 52.07) (xy 135.255 52.705)
		)
		(stroke
			(width 0)
			(type default)
		)
	)
	(wire
		(pts
			(xy 135.255 182.88) (xy 135.255 183.515)
		)
		(stroke
			(width 0)
			(type default)
		)
	)
	(wire
		(pts
			(xy 121.285 82.55) (xy 121.285 83.185)
		)
		(stroke
			(width 0)
			(type default)
		)
	)
	(wire
		(pts
			(xy 114.3 45.72) (xy 114.3 46.99)
		)
		(stroke
			(width 0)
			(type default)
		)
	)
	(wire
		(pts
			(xy 198.12 66.04) (xy 196.85 66.04)
		)
		(stroke
			(width 0)
			(type default)
		)
	)
	(wire
		(pts
			(xy 198.12 83.82) (xy 180.975 83.82)
		)
		(stroke
			(width 0)
			(type default)
		)
	)
	(wire
		(pts
			(xy 121.285 146.05) (xy 128.27 146.05)
		)
		(stroke
			(width 0)
			(type default)
		)
	)
	(wire
		(pts
			(xy 114.3 168.275) (xy 114.3 167.64)
		)
		(stroke
			(width 0)
			(type default)
		)
	)
	(wire
		(pts
			(xy 198.12 68.58) (xy 187.96 68.58)
		)
		(stroke
			(width 0)
			(type default)
		)
	)
	(wire
		(pts
			(xy 167.005 146.05) (xy 167.005 166.37)
		)
		(stroke
			(width 0)
			(type default)
		)
	)
	(wire
		(pts
			(xy 142.24 146.05) (xy 142.24 147.32)
		)
		(stroke
			(width 0)
			(type default)
		)
	)
	(wire
		(pts
			(xy 142.24 146.05) (xy 149.225 146.05)
		)
		(stroke
			(width 0)
			(type default)
		)
	)
	(wire
		(pts
			(xy 114.3 161.29) (xy 114.3 162.56)
		)
		(stroke
			(width 0)
			(type default)
		)
	)
	(wire
		(pts
			(xy 187.96 61.595) (xy 187.96 62.23)
		)
		(stroke
			(width 0)
			(type default)
		)
	)
	(wire
		(pts
			(xy 183.515 68.58) (xy 187.96 68.58)
		)
		(stroke
			(width 0)
			(type default)
		)
	)
	(wire
		(pts
			(xy 238.76 106.68) (xy 245.745 106.68)
		)
		(stroke
			(width 0)
			(type default)
		)
	)
	(wire
		(pts
			(xy 112.395 146.05) (xy 114.3 146.05)
		)
		(stroke
			(width 0)
			(type default)
		)
	)
	(wire
		(pts
			(xy 121.285 161.29) (xy 121.285 162.56)
		)
		(stroke
			(width 0)
			(type default)
		)
	)
	(wire
		(pts
			(xy 185.42 186.69) (xy 189.23 186.69)
		)
		(stroke
			(width 0)
			(type default)
		)
	)
	(wire
		(pts
			(xy 149.225 176.53) (xy 156.21 176.53)
		)
		(stroke
			(width 0)
			(type default)
		)
	)
	(wire
		(pts
			(xy 189.23 186.69) (xy 198.12 186.69)
		)
		(stroke
			(width 0)
			(type default)
		)
	)
	(wire
		(pts
			(xy 135.255 83.185) (xy 135.255 82.55)
		)
		(stroke
			(width 0)
			(type default)
		)
	)
	(wire
		(pts
			(xy 135.255 146.05) (xy 142.24 146.05)
		)
		(stroke
			(width 0)
			(type default)
		)
	)
	(wire
		(pts
			(xy 198.12 224.79) (xy 196.85 224.79)
		)
		(stroke
			(width 0)
			(type default)
		)
	)
	(wire
		(pts
			(xy 238.76 88.9) (xy 246.38 88.9)
		)
		(stroke
			(width 0)
			(type default)
		)
	)
	(wire
		(pts
			(xy 128.27 76.2) (xy 128.27 77.47)
		)
		(stroke
			(width 0)
			(type default)
		)
	)
	(wire
		(pts
			(xy 135.255 76.2) (xy 135.255 77.47)
		)
		(stroke
			(width 0)
			(type default)
		)
	)
	(wire
		(pts
			(xy 156.21 83.185) (xy 156.21 82.55)
		)
		(stroke
			(width 0)
			(type default)
		)
	)
	(wire
		(pts
			(xy 198.12 86.36) (xy 180.975 86.36)
		)
		(stroke
			(width 0)
			(type default)
		)
	)
	(wire
		(pts
			(xy 142.24 82.55) (xy 142.24 83.185)
		)
		(stroke
			(width 0)
			(type default)
		)
	)
	(wire
		(pts
			(xy 189.23 126.365) (xy 189.23 127)
		)
		(stroke
			(width 0)
			(type default)
		)
	)
	(wire
		(pts
			(xy 149.225 146.05) (xy 156.21 146.05)
		)
		(stroke
			(width 0)
			(type default)
		)
	)
	(wire
		(pts
			(xy 113.665 161.29) (xy 114.3 161.29)
		)
		(stroke
			(width 0)
			(type default)
		)
	)
	(wire
		(pts
			(xy 114.3 67.945) (xy 114.3 67.31)
		)
		(stroke
			(width 0)
			(type default)
		)
	)
	(wire
		(pts
			(xy 135.255 146.05) (xy 135.255 147.32)
		)
		(stroke
			(width 0)
			(type default)
		)
	)
	(wire
		(pts
			(xy 114.3 146.05) (xy 121.285 146.05)
		)
		(stroke
			(width 0)
			(type default)
		)
	)
	(wire
		(pts
			(xy 184.15 217.17) (xy 189.865 217.17)
		)
		(stroke
			(width 0)
			(type default)
		)
	)
	(wire
		(pts
			(xy 142.24 182.88) (xy 142.24 183.515)
		)
		(stroke
			(width 0)
			(type default)
		)
	)
	(wire
		(pts
			(xy 156.21 176.53) (xy 156.21 177.8)
		)
		(stroke
			(width 0)
			(type default)
		)
	)
	(wire
		(pts
			(xy 156.21 182.88) (xy 156.21 183.515)
		)
		(stroke
			(width 0)
			(type default)
		)
	)
	(wire
		(pts
			(xy 173.355 106.68) (xy 174.625 106.68)
		)
		(stroke
			(width 0)
			(type default)
		)
	)
	(wire
		(pts
			(xy 163.195 182.88) (xy 163.195 183.515)
		)
		(stroke
			(width 0)
			(type default)
		)
	)
	(wire
		(pts
			(xy 128.27 60.96) (xy 128.27 62.23)
		)
		(stroke
			(width 0)
			(type default)
		)
	)
	(wire
		(pts
			(xy 128.27 45.72) (xy 135.255 45.72)
		)
		(stroke
			(width 0)
			(type default)
		)
	)
	(polyline
		(pts
			(xy 119.38 283.845) (xy 118.745 283.845)
		)
		(stroke
			(width 0)
			(type default)
		)
	)
	(wire
		(pts
			(xy 174.625 116.84) (xy 198.12 116.84)
		)
		(stroke
			(width 0)
			(type default)
		)
	)
	(wire
		(pts
			(xy 121.285 52.07) (xy 121.285 52.705)
		)
		(stroke
			(width 0)
			(type default)
		)
	)
	(wire
		(pts
			(xy 121.285 60.96) (xy 121.285 62.23)
		)
		(stroke
			(width 0)
			(type default)
		)
	)
	(wire
		(pts
			(xy 149.225 45.72) (xy 149.225 46.99)
		)
		(stroke
			(width 0)
			(type default)
		)
	)
	(wire
		(pts
			(xy 156.21 76.2) (xy 163.195 76.2)
		)
		(stroke
			(width 0)
			(type default)
		)
	)
	(wire
		(pts
			(xy 135.255 152.4) (xy 135.255 153.035)
		)
		(stroke
			(width 0)
			(type default)
		)
	)
	(wire
		(pts
			(xy 238.76 119.38) (xy 245.745 119.38)
		)
		(stroke
			(width 0)
			(type default)
		)
	)
	(wire
		(pts
			(xy 142.24 153.035) (xy 142.24 152.4)
		)
		(stroke
			(width 0)
			(type default)
		)
	)
	(wire
		(pts
			(xy 189.23 120.65) (xy 189.23 121.285)
		)
		(stroke
			(width 0)
			(type default)
		)
	)
	(wire
		(pts
			(xy 174.625 106.68) (xy 174.625 109.22)
		)
		(stroke
			(width 0)
			(type default)
		)
	)
	(wire
		(pts
			(xy 142.24 73.66) (xy 142.24 60.96)
		)
		(stroke
			(width 0)
			(type default)
		)
	)
	(wire
		(pts
			(xy 142.24 52.07) (xy 142.24 52.705)
		)
		(stroke
			(width 0)
			(type default)
		)
	)
	(wire
		(pts
			(xy 135.255 45.72) (xy 142.24 45.72)
		)
		(stroke
			(width 0)
			(type default)
		)
	)
	(wire
		(pts
			(xy 121.285 67.945) (xy 121.285 67.31)
		)
		(stroke
			(width 0)
			(type default)
		)
	)
	(wire
		(pts
			(xy 121.285 176.53) (xy 121.285 177.8)
		)
		(stroke
			(width 0)
			(type default)
		)
	)
	(wire
		(pts
			(xy 114.3 45.72) (xy 121.285 45.72)
		)
		(stroke
			(width 0)
			(type default)
		)
	)
	(wire
		(pts
			(xy 198.12 106.68) (xy 190.5 106.68)
		)
		(stroke
			(width 0)
			(type default)
		)
	)
	(wire
		(pts
			(xy 142.24 45.72) (xy 149.225 45.72)
		)
		(stroke
			(width 0)
			(type default)
		)
	)
	(wire
		(pts
			(xy 238.76 76.2) (xy 246.38 76.2)
		)
		(stroke
			(width 0)
			(type default)
		)
	)
	(wire
		(pts
			(xy 238.76 114.3) (xy 245.745 114.3)
		)
		(stroke
			(width 0)
			(type default)
		)
	)
	(wire
		(pts
			(xy 156.21 146.05) (xy 167.005 146.05)
		)
		(stroke
			(width 0)
			(type default)
		)
	)
	(wire
		(pts
			(xy 163.195 176.53) (xy 198.12 176.53)
		)
		(stroke
			(width 0)
			(type default)
		)
	)
	(wire
		(pts
			(xy 163.195 83.185) (xy 163.195 82.55)
		)
		(stroke
			(width 0)
			(type default)
		)
	)
	(wire
		(pts
			(xy 238.76 124.46) (xy 245.745 124.46)
		)
		(stroke
			(width 0)
			(type default)
		)
	)
	(wire
		(pts
			(xy 149.225 82.55) (xy 149.225 83.185)
		)
		(stroke
			(width 0)
			(type default)
		)
	)
	(wire
		(pts
			(xy 198.12 99.06) (xy 190.5 99.06)
		)
		(stroke
			(width 0)
			(type default)
		)
	)
	(wire
		(pts
			(xy 112.395 45.72) (xy 114.3 45.72)
		)
		(stroke
			(width 0)
			(type default)
		)
	)
	(wire
		(pts
			(xy 238.76 101.6) (xy 245.745 101.6)
		)
		(stroke
			(width 0)
			(type default)
		)
	)
	(wire
		(pts
			(xy 135.255 176.53) (xy 142.24 176.53)
		)
		(stroke
			(width 0)
			(type default)
		)
	)
	(wire
		(pts
			(xy 167.005 61.595) (xy 187.96 61.595)
		)
		(stroke
			(width 0)
			(type default)
		)
	)
	(wire
		(pts
			(xy 135.255 176.53) (xy 135.255 177.8)
		)
		(stroke
			(width 0)
			(type default)
		)
	)
	(wire
		(pts
			(xy 121.285 76.2) (xy 121.285 77.47)
		)
		(stroke
			(width 0)
			(type default)
		)
	)
	(wire
		(pts
			(xy 114.3 182.88) (xy 114.3 183.515)
		)
		(stroke
			(width 0)
			(type default)
		)
	)
	(wire
		(pts
			(xy 238.76 99.06) (xy 245.745 99.06)
		)
		(stroke
			(width 0)
			(type default)
		)
	)
	(wire
		(pts
			(xy 163.195 176.53) (xy 163.195 177.8)
		)
		(stroke
			(width 0)
			(type default)
		)
	)
	(wire
		(pts
			(xy 114.3 176.53) (xy 114.3 177.8)
		)
		(stroke
			(width 0)
			(type default)
		)
	)
	(wire
		(pts
			(xy 142.24 76.2) (xy 149.225 76.2)
		)
		(stroke
			(width 0)
			(type default)
		)
	)
	(wire
		(pts
			(xy 238.76 83.82) (xy 246.38 83.82)
		)
		(stroke
			(width 0)
			(type default)
		)
	)
	(wire
		(pts
			(xy 163.195 76.2) (xy 163.195 77.47)
		)
		(stroke
			(width 0)
			(type default)
		)
	)
	(wire
		(pts
			(xy 114.3 161.29) (xy 121.285 161.29)
		)
		(stroke
			(width 0)
			(type default)
		)
	)
	(wire
		(pts
			(xy 238.76 68.58) (xy 246.38 68.58)
		)
		(stroke
			(width 0)
			(type default)
		)
	)
	(wire
		(pts
			(xy 149.225 76.2) (xy 156.21 76.2)
		)
		(stroke
			(width 0)
			(type default)
		)
	)
	(wire
		(pts
			(xy 121.285 60.96) (xy 128.27 60.96)
		)
		(stroke
			(width 0)
			(type default)
		)
	)
	(wire
		(pts
			(xy 169.545 116.84) (xy 174.625 116.84)
		)
		(stroke
			(width 0)
			(type default)
		)
	)
	(wire
		(pts
			(xy 174.625 114.3) (xy 174.625 116.84)
		)
		(stroke
			(width 0)
			(type default)
		)
	)
	(wire
		(pts
			(xy 198.12 96.52) (xy 190.5 96.52)
		)
		(stroke
			(width 0)
			(type default)
		)
	)
	(wire
		(pts
			(xy 121.285 76.2) (xy 128.27 76.2)
		)
		(stroke
			(width 0)
			(type default)
		)
	)
	(wire
		(pts
			(xy 128.27 52.07) (xy 128.27 52.705)
		)
		(stroke
			(width 0)
			(type default)
		)
	)
	(wire
		(pts
			(xy 156.21 52.07) (xy 156.21 52.705)
		)
		(stroke
			(width 0)
			(type default)
		)
	)
	(wire
		(pts
			(xy 114.3 82.55) (xy 114.3 83.185)
		)
		(stroke
			(width 0)
			(type default)
		)
	)
	(wire
		(pts
			(xy 189.23 187.325) (xy 189.23 186.69)
		)
		(stroke
			(width 0)
			(type default)
		)
	)
	(wire
		(pts
			(xy 114.3 176.53) (xy 121.285 176.53)
		)
		(stroke
			(width 0)
			(type default)
		)
	)
	(wire
		(pts
			(xy 160.02 116.84) (xy 164.465 116.84)
		)
		(stroke
			(width 0)
			(type default)
		)
	)
	(wire
		(pts
			(xy 156.21 45.72) (xy 167.005 45.72)
		)
		(stroke
			(width 0)
			(type default)
		)
	)
	(wire
		(pts
			(xy 238.76 91.44) (xy 246.38 91.44)
		)
		(stroke
			(width 0)
			(type default)
		)
	)
	(wire
		(pts
			(xy 238.76 73.66) (xy 246.38 73.66)
		)
		(stroke
			(width 0)
			(type default)
		)
	)
	(wire
		(pts
			(xy 156.21 152.4) (xy 156.21 153.035)
		)
		(stroke
			(width 0)
			(type default)
		)
	)
	(wire
		(pts
			(xy 156.21 176.53) (xy 163.195 176.53)
		)
		(stroke
			(width 0)
			(type default)
		)
	)
	(wire
		(pts
			(xy 142.24 176.53) (xy 142.24 177.8)
		)
		(stroke
			(width 0)
			(type default)
		)
	)
	(wire
		(pts
			(xy 112.395 176.53) (xy 114.3 176.53)
		)
		(stroke
			(width 0)
			(type default)
		)
	)
	(wire
		(pts
			(xy 121.285 45.72) (xy 128.27 45.72)
		)
		(stroke
			(width 0)
			(type default)
		)
	)
	(wire
		(pts
			(xy 238.76 104.14) (xy 245.745 104.14)
		)
		(stroke
			(width 0)
			(type default)
		)
	)
	(wire
		(pts
			(xy 142.24 176.53) (xy 149.225 176.53)
		)
		(stroke
			(width 0)
			(type default)
		)
	)
	(wire
		(pts
			(xy 121.285 182.88) (xy 121.285 183.515)
		)
		(stroke
			(width 0)
			(type default)
		)
	)
	(wire
		(pts
			(xy 196.85 124.46) (xy 198.12 124.46)
		)
		(stroke
			(width 0)
			(type default)
		)
	)
	(wire
		(pts
			(xy 128.27 146.05) (xy 128.27 147.32)
		)
		(stroke
			(width 0)
			(type default)
		)
	)
	(wire
		(pts
			(xy 128.27 67.945) (xy 128.27 67.31)
		)
		(stroke
			(width 0)
			(type default)
		)
	)
	(wire
		(pts
			(xy 149.225 52.705) (xy 149.225 52.07)
		)
		(stroke
			(width 0)
			(type default)
		)
	)
	(wire
		(pts
			(xy 163.195 76.2) (xy 198.12 76.2)
		)
		(stroke
			(width 0)
			(type default)
		)
	)
	(wire
		(pts
			(xy 238.76 81.28) (xy 246.38 81.28)
		)
		(stroke
			(width 0)
			(type default)
		)
	)
	(wire
		(pts
			(xy 238.76 66.04) (xy 246.38 66.04)
		)
		(stroke
			(width 0)
			(type default)
		)
	)
	(wire
		(pts
			(xy 128.27 152.4) (xy 128.27 153.035)
		)
		(stroke
			(width 0)
			(type default)
		)
	)
	(wire
		(pts
			(xy 128.27 146.05) (xy 135.255 146.05)
		)
		(stroke
			(width 0)
			(type default)
		)
	)
	(wire
		(pts
			(xy 121.285 45.72) (xy 121.285 46.99)
		)
		(stroke
			(width 0)
			(type default)
		)
	)
	(wire
		(pts
			(xy 114.3 76.2) (xy 121.285 76.2)
		)
		(stroke
			(width 0)
			(type default)
		)
	)
	(wire
		(pts
			(xy 167.005 166.37) (xy 198.12 166.37)
		)
		(stroke
			(width 0)
			(type default)
		)
	)
	(wire
		(pts
			(xy 187.96 68.58) (xy 187.96 67.31)
		)
		(stroke
			(width 0)
			(type default)
		)
	)
	(wire
		(pts
			(xy 114.3 146.05) (xy 114.3 147.32)
		)
		(stroke
			(width 0)
			(type default)
		)
	)
	(wire
		(pts
			(xy 114.3 52.07) (xy 114.3 52.705)
		)
		(stroke
			(width 0)
			(type default)
		)
	)
	(wire
		(pts
			(xy 238.76 109.22) (xy 245.745 109.22)
		)
		(stroke
			(width 0)
			(type default)
		)
	)
	(wire
		(pts
			(xy 149.225 152.4) (xy 149.225 153.035)
		)
		(stroke
			(width 0)
			(type default)
		)
	)
	(wire
		(pts
			(xy 156.21 76.2) (xy 156.21 77.47)
		)
		(stroke
			(width 0)
			(type default)
		)
	)
	(wire
		(pts
			(xy 121.285 152.4) (xy 121.285 153.035)
		)
		(stroke
			(width 0)
			(type default)
		)
	)
	(wire
		(pts
			(xy 238.76 116.84) (xy 245.745 116.84)
		)
		(stroke
			(width 0)
			(type default)
		)
	)
	(wire
		(pts
			(xy 238.76 71.12) (xy 246.38 71.12)
		)
		(stroke
			(width 0)
			(type default)
		)
	)
	(wire
		(pts
			(xy 198.12 81.28) (xy 180.975 81.28)
		)
		(stroke
			(width 0)
			(type default)
		)
	)
	(wire
		(pts
			(xy 196.85 224.79) (xy 196.85 226.06)
		)
		(stroke
			(width 0)
			(type default)
		)
	)
	(wire
		(pts
			(xy 142.24 76.2) (xy 142.24 77.47)
		)
		(stroke
			(width 0)
			(type default)
		)
	)
	(wire
		(pts
			(xy 198.12 173.99) (xy 142.24 173.99)
		)
		(stroke
			(width 0)
			(type default)
		)
	)
	(wire
		(pts
			(xy 142.24 45.72) (xy 142.24 46.99)
		)
		(stroke
			(width 0)
			(type default)
		)
	)
	(wire
		(pts
			(xy 121.285 146.05) (xy 121.285 147.32)
		)
		(stroke
			(width 0)
			(type default)
		)
	)
	(wire
		(pts
			(xy 196.85 61.595) (xy 196.85 66.04)
		)
		(stroke
			(width 0)
			(type default)
		)
	)
	(wire
		(pts
			(xy 128.27 76.2) (xy 135.255 76.2)
		)
		(stroke
			(width 0)
			(type default)
		)
	)
	(wire
		(pts
			(xy 121.285 176.53) (xy 128.27 176.53)
		)
		(stroke
			(width 0)
			(type default)
		)
	)
	(wire
		(pts
			(xy 189.23 120.65) (xy 198.12 120.65)
		)
		(stroke
			(width 0)
			(type default)
		)
	)
	(wire
		(pts
			(xy 114.3 60.96) (xy 114.3 62.23)
		)
		(stroke
			(width 0)
			(type default)
		)
	)
	(wire
		(pts
			(xy 149.225 146.05) (xy 149.225 147.32)
		)
		(stroke
			(width 0)
			(type default)
		)
	)
	(wire
		(pts
			(xy 167.005 45.72) (xy 167.005 61.595)
		)
		(stroke
			(width 0)
			(type default)
		)
	)
	(wire
		(pts
			(xy 121.285 168.275) (xy 121.285 167.64)
		)
		(stroke
			(width 0)
			(type default)
		)
	)
	(wire
		(pts
			(xy 238.76 86.36) (xy 246.38 86.36)
		)
		(stroke
			(width 0)
			(type default)
		)
	)
	(wire
		(pts
			(xy 156.21 146.05) (xy 156.21 147.32)
		)
		(stroke
			(width 0)
			(type default)
		)
	)
	(wire
		(pts
			(xy 238.76 78.74) (xy 246.38 78.74)
		)
		(stroke
			(width 0)
			(type default)
		)
	)
	(global_label "CA0_A"
		(shape input)
		(at 190.5 93.98 180)
		(fields_autoplaced yes)
		(effects
			(font
				(size 1.27 1.27)
			)
			(justify right)
		)
		(property "Intersheetrefs" "${INTERSHEET_REFS}"
			(at 182.5515 93.9006 0)
			(effects
				(font
					(size 1.27 1.27)
				)
				(justify right)
				(hide yes)
			)
		)
	)
	(global_label "CK_T_A"
		(shape input)
		(at 180.975 81.28 180)
		(fields_autoplaced yes)
		(effects
			(font
				(size 1.27 1.27)
			)
			(justify right)
		)
		(property "Intersheetrefs" "${INTERSHEET_REFS}"
			(at 172.1194 81.2006 0)
			(effects
				(font
					(size 1.27 1.27)
				)
				(justify right)
				(hide yes)
			)
		)
	)
	(global_label "CA2_A"
		(shape input)
		(at 190.5 99.06 180)
		(fields_autoplaced yes)
		(effects
			(font
				(size 1.27 1.27)
			)
			(justify right)
		)
		(property "Intersheetrefs" "${INTERSHEET_REFS}"
			(at 100.33 8.89 0)
			(effects
				(font
					(size 1.27 1.27)
				)
				(hide yes)
			)
		)
	)
	(global_label "CA5_A"
		(shape input)
		(at 190.5 106.68 180)
		(fields_autoplaced yes)
		(effects
			(font
				(size 1.27 1.27)
			)
			(justify right)
		)
		(property "Intersheetrefs" "${INTERSHEET_REFS}"
			(at 100.33 8.89 0)
			(effects
				(font
					(size 1.27 1.27)
				)
				(hide yes)
			)
		)
	)
	(global_label "VDD1"
		(shape input)
		(at 113.665 161.29 180)
		(fields_autoplaced yes)
		(effects
			(font
				(size 1.27 1.27)
			)
			(justify right)
		)
		(property "Intersheetrefs" "${INTERSHEET_REFS}"
			(at 106.5027 161.2106 0)
			(effects
				(font
					(size 1.27 1.27)
				)
				(justify right)
				(hide yes)
			)
		)
	)
	(global_label "DQ_S0_CA"
		(shape input)
		(at 246.38 68.58 0)
		(fields_autoplaced yes)
		(effects
			(font
				(size 1.27 1.27)
			)
			(justify left)
		)
		(property "Intersheetrefs" "${INTERSHEET_REFS}"
			(at 336.55 -41.91 0)
			(effects
				(font
					(size 1.27 1.27)
				)
				(justify left)
				(hide yes)
			)
		)
	)
	(global_label "DQ01_A"
		(shape input)
		(at 246.38 73.66 0)
		(fields_autoplaced yes)
		(effects
			(font
				(size 1.27 1.27)
			)
			(justify left)
		)
		(property "Intersheetrefs" "${INTERSHEET_REFS}"
			(at 336.55 -41.91 0)
			(effects
				(font
					(size 1.27 1.27)
				)
				(justify left)
				(hide yes)
			)
		)
	)
	(global_label "CS0_A"
		(shape input)
		(at 180.975 86.36 180)
		(fields_autoplaced yes)
		(effects
			(font
				(size 1.27 1.27)
			)
			(justify right)
		)
		(property "Intersheetrefs" "${INTERSHEET_REFS}"
			(at 100.33 8.89 0)
			(effects
				(font
					(size 1.27 1.27)
				)
				(hide yes)
			)
		)
	)
	(global_label "VDDQ"
		(shape input)
		(at 112.395 146.05 180)
		(fields_autoplaced yes)
		(effects
			(font
				(size 1.27 1.27)
			)
			(justify right)
		)
		(property "Intersheetrefs" "${INTERSHEET_REFS}"
			(at 53.975 266.7 0)
			(effects
				(font
					(size 1.27 1.27)
				)
				(hide yes)
			)
		)
	)
	(global_label "DQ05_A"
		(shape input)
		(at 246.38 83.82 0)
		(fields_autoplaced yes)
		(effects
			(font
				(size 1.27 1.27)
			)
			(justify left)
		)
		(property "Intersheetrefs" "${INTERSHEET_REFS}"
			(at 336.55 -41.91 0)
			(effects
				(font
					(size 1.27 1.27)
				)
				(justify left)
				(hide yes)
			)
		)
	)
	(global_label "VDD2"
		(shape input)
		(at 112.395 176.53 180)
		(fields_autoplaced yes)
		(effects
			(font
				(size 1.27 1.27)
			)
			(justify right)
		)
		(property "Intersheetrefs" "${INTERSHEET_REFS}"
			(at -134.62 206.375 0)
			(effects
				(font
					(size 1.27 1.27)
				)
				(hide yes)
			)
		)
	)
	(global_label "DQ07_A"
		(shape input)
		(at 246.38 88.9 0)
		(fields_autoplaced yes)
		(effects
			(font
				(size 1.27 1.27)
			)
			(justify left)
		)
		(property "Intersheetrefs" "${INTERSHEET_REFS}"
			(at 336.55 -41.91 0)
			(effects
				(font
					(size 1.27 1.27)
				)
				(justify left)
				(hide yes)
			)
		)
	)
	(global_label "VDD1"
		(shape input)
		(at 112.395 60.96 180)
		(fields_autoplaced yes)
		(effects
			(font
				(size 1.27 1.27)
			)
			(justify right)
		)
		(property "Intersheetrefs" "${INTERSHEET_REFS}"
			(at 105.2327 60.8806 0)
			(effects
				(font
					(size 1.27 1.27)
				)
				(justify right)
				(hide yes)
			)
		)
	)
	(global_label "DQ13_A"
		(shape input)
		(at 245.745 116.84 0)
		(fields_autoplaced yes)
		(effects
			(font
				(size 1.27 1.27)
			)
			(justify left)
		)
		(property "Intersheetrefs" "${INTERSHEET_REFS}"
			(at 100.33 -8.89 0)
			(effects
				(font
					(size 1.27 1.27)
				)
				(hide yes)
			)
		)
	)
	(global_label "DQ_S0_TA"
		(shape input)
		(at 246.38 66.04 0)
		(fields_autoplaced yes)
		(effects
			(font
				(size 1.27 1.27)
			)
			(justify left)
		)
		(property "Intersheetrefs" "${INTERSHEET_REFS}"
			(at 336.55 -41.91 0)
			(effects
				(font
					(size 1.27 1.27)
				)
				(justify left)
				(hide yes)
			)
		)
	)
	(global_label "DQ02_A"
		(shape input)
		(at 246.38 76.2 0)
		(fields_autoplaced yes)
		(effects
			(font
				(size 1.27 1.27)
			)
			(justify left)
		)
		(property "Intersheetrefs" "${INTERSHEET_REFS}"
			(at 336.55 -41.91 0)
			(effects
				(font
					(size 1.27 1.27)
				)
				(justify left)
				(hide yes)
			)
		)
	)
	(global_label "DQ04_A"
		(shape input)
		(at 246.38 81.28 0)
		(fields_autoplaced yes)
		(effects
			(font
				(size 1.27 1.27)
			)
			(justify left)
		)
		(property "Intersheetrefs" "${INTERSHEET_REFS}"
			(at 336.55 -41.91 0)
			(effects
				(font
					(size 1.27 1.27)
				)
				(justify left)
				(hide yes)
			)
		)
	)
	(global_label "DMI_0A"
		(shape input)
		(at 246.38 91.44 0)
		(fields_autoplaced yes)
		(effects
			(font
				(size 1.27 1.27)
			)
			(justify left)
		)
		(property "Intersheetrefs" "${INTERSHEET_REFS}"
			(at 336.55 -41.91 0)
			(effects
				(font
					(size 1.27 1.27)
				)
				(justify left)
				(hide yes)
			)
		)
	)
	(global_label "ODT_CA_A"
		(shape input)
		(at 160.02 116.84 180)
		(fields_autoplaced yes)
		(effects
			(font
				(size 1.27 1.27)
			)
			(justify right)
		)
		(property "Intersheetrefs" "${INTERSHEET_REFS}"
			(at 148.7453 116.7606 0)
			(effects
				(font
					(size 1.27 1.27)
				)
				(justify right)
				(hide yes)
			)
		)
	)
	(global_label "DQ09_A"
		(shape input)
		(at 245.745 106.68 0)
		(fields_autoplaced yes)
		(effects
			(font
				(size 1.27 1.27)
			)
			(justify left)
		)
		(property "Intersheetrefs" "${INTERSHEET_REFS}"
			(at 100.33 -8.89 0)
			(effects
				(font
					(size 1.27 1.27)
				)
				(hide yes)
			)
		)
	)
	(global_label "DQ15_A"
		(shape input)
		(at 245.745 121.92 0)
		(fields_autoplaced yes)
		(effects
			(font
				(size 1.27 1.27)
			)
			(justify left)
		)
		(property "Intersheetrefs" "${INTERSHEET_REFS}"
			(at 100.33 -8.89 0)
			(effects
				(font
					(size 1.27 1.27)
				)
				(hide yes)
			)
		)
	)
	(global_label "CA1_A"
		(shape input)
		(at 190.5 96.52 180)
		(fields_autoplaced yes)
		(effects
			(font
				(size 1.27 1.27)
			)
			(justify right)
		)
		(property "Intersheetrefs" "${INTERSHEET_REFS}"
			(at 182.5515 96.4406 0)
			(effects
				(font
					(size 1.27 1.27)
				)
				(justify right)
				(hide yes)
			)
		)
	)
	(global_label "DQ10_A"
		(shape input)
		(at 245.745 109.22 0)
		(fields_autoplaced yes)
		(effects
			(font
				(size 1.27 1.27)
			)
			(justify left)
		)
		(property "Intersheetrefs" "${INTERSHEET_REFS}"
			(at 100.33 -8.89 0)
			(effects
				(font
					(size 1.27 1.27)
				)
				(hide yes)
			)
		)
	)
	(global_label "VDDQ"
		(shape input)
		(at 173.355 106.68 180)
		(fields_autoplaced yes)
		(effects
			(font
				(size 1.27 1.27)
			)
			(justify right)
		)
		(property "Intersheetrefs" "${INTERSHEET_REFS}"
			(at 114.935 -36.195 90)
			(effects
				(font
					(size 1.27 1.27)
				)
				(justify left)
				(hide yes)
			)
		)
	)
	(global_label "RESET_N"
		(shape input)
		(at 175.26 68.58 180)
		(fields_autoplaced yes)
		(effects
			(font
				(size 1.27 1.27)
			)
			(justify right)
		)
		(property "Intersheetrefs" "${INTERSHEET_REFS}"
			(at 508.635 -6.35 0)
			(effects
				(font
					(size 1.27 1.27)
				)
				(justify left)
				(hide yes)
			)
		)
	)
	(global_label "VDDQ"
		(shape input)
		(at 184.15 217.17 180)
		(fields_autoplaced yes)
		(effects
			(font
				(size 1.27 1.27)
			)
			(justify right)
		)
		(property "Intersheetrefs" "${INTERSHEET_REFS}"
			(at 125.73 -88.9 90)
			(effects
				(font
					(size 1.27 1.27)
				)
				(justify left)
				(hide yes)
			)
		)
	)
	(global_label "DQ08_A"
		(shape input)
		(at 245.745 104.14 0)
		(fields_autoplaced yes)
		(effects
			(font
				(size 1.27 1.27)
			)
			(justify left)
		)
		(property "Intersheetrefs" "${INTERSHEET_REFS}"
			(at 100.33 -8.89 0)
			(effects
				(font
					(size 1.27 1.27)
				)
				(hide yes)
			)
		)
	)
	(global_label "CKE0_A"
		(shape input)
		(at 190.5 109.22 180)
		(fields_autoplaced yes)
		(effects
			(font
				(size 1.27 1.27)
			)
			(justify right)
		)
		(property "Intersheetrefs" "${INTERSHEET_REFS}"
			(at 100.33 8.89 0)
			(effects
				(font
					(size 1.27 1.27)
				)
				(hide yes)
			)
		)
	)
	(global_label "DQ11_A"
		(shape input)
		(at 245.745 111.76 0)
		(fields_autoplaced yes)
		(effects
			(font
				(size 1.27 1.27)
			)
			(justify left)
		)
		(property "Intersheetrefs" "${INTERSHEET_REFS}"
			(at 100.33 -8.89 0)
			(effects
				(font
					(size 1.27 1.27)
				)
				(hide yes)
			)
		)
	)
	(global_label "DQ00_A"
		(shape input)
		(at 246.38 71.12 0)
		(fields_autoplaced yes)
		(effects
			(font
				(size 1.27 1.27)
			)
			(justify left)
		)
		(property "Intersheetrefs" "${INTERSHEET_REFS}"
			(at 336.55 -41.91 0)
			(effects
				(font
					(size 1.27 1.27)
				)
				(justify left)
				(hide yes)
			)
		)
	)
	(global_label "DQ_S1_CA"
		(shape input)
		(at 245.745 101.6 0)
		(fields_autoplaced yes)
		(effects
			(font
				(size 1.27 1.27)
			)
			(justify left)
		)
		(property "Intersheetrefs" "${INTERSHEET_REFS}"
			(at 100.33 -8.89 0)
			(effects
				(font
					(size 1.27 1.27)
				)
				(hide yes)
			)
		)
	)
	(global_label "CK_C_A"
		(shape input)
		(at 180.975 83.82 180)
		(fields_autoplaced yes)
		(effects
			(font
				(size 1.27 1.27)
			)
			(justify right)
		)
		(property "Intersheetrefs" "${INTERSHEET_REFS}"
			(at 171.817 83.7406 0)
			(effects
				(font
					(size 1.27 1.27)
				)
				(justify right)
				(hide yes)
			)
		)
	)
	(global_label "CA4_A"
		(shape input)
		(at 190.5 104.14 180)
		(fields_autoplaced yes)
		(effects
			(font
				(size 1.27 1.27)
			)
			(justify right)
		)
		(property "Intersheetrefs" "${INTERSHEET_REFS}"
			(at 100.33 8.89 0)
			(effects
				(font
					(size 1.27 1.27)
				)
				(hide yes)
			)
		)
	)
	(global_label "DQ06_A"
		(shape input)
		(at 246.38 86.36 0)
		(fields_autoplaced yes)
		(effects
			(font
				(size 1.27 1.27)
			)
			(justify left)
		)
		(property "Intersheetrefs" "${INTERSHEET_REFS}"
			(at 336.55 -41.91 0)
			(effects
				(font
					(size 1.27 1.27)
				)
				(justify left)
				(hide yes)
			)
		)
	)
	(global_label "VDD2"
		(shape input)
		(at 113.03 76.2 180)
		(fields_autoplaced yes)
		(effects
			(font
				(size 1.27 1.27)
			)
			(justify right)
		)
		(property "Intersheetrefs" "${INTERSHEET_REFS}"
			(at -133.985 106.045 0)
			(effects
				(font
					(size 1.27 1.27)
				)
				(hide yes)
			)
		)
	)
	(global_label "DQ_S1_TA"
		(shape input)
		(at 245.745 99.06 0)
		(fields_autoplaced yes)
		(effects
			(font
				(size 1.27 1.27)
			)
			(justify left)
		)
		(property "Intersheetrefs" "${INTERSHEET_REFS}"
			(at 100.33 -8.89 0)
			(effects
				(font
					(size 1.27 1.27)
				)
				(hide yes)
			)
		)
	)
	(global_label "DQ12_A"
		(shape input)
		(at 245.745 114.3 0)
		(fields_autoplaced yes)
		(effects
			(font
				(size 1.27 1.27)
			)
			(justify left)
		)
		(property "Intersheetrefs" "${INTERSHEET_REFS}"
			(at 100.33 -8.89 0)
			(effects
				(font
					(size 1.27 1.27)
				)
				(hide yes)
			)
		)
	)
	(global_label "CA3_A"
		(shape input)
		(at 190.5 101.6 180)
		(fields_autoplaced yes)
		(effects
			(font
				(size 1.27 1.27)
			)
			(justify right)
		)
		(property "Intersheetrefs" "${INTERSHEET_REFS}"
			(at 100.33 8.89 0)
			(effects
				(font
					(size 1.27 1.27)
				)
				(hide yes)
			)
		)
	)
	(global_label "DMI_1A"
		(shape input)
		(at 245.745 124.46 0)
		(fields_autoplaced yes)
		(effects
			(font
				(size 1.27 1.27)
			)
			(justify left)
		)
		(property "Intersheetrefs" "${INTERSHEET_REFS}"
			(at 100.33 -8.89 0)
			(effects
				(font
					(size 1.27 1.27)
				)
				(hide yes)
			)
		)
	)
	(global_label "DQ14_A"
		(shape input)
		(at 245.745 119.38 0)
		(fields_autoplaced yes)
		(effects
			(font
				(size 1.27 1.27)
			)
			(justify left)
		)
		(property "Intersheetrefs" "${INTERSHEET_REFS}"
			(at 100.33 -8.89 0)
			(effects
				(font
					(size 1.27 1.27)
				)
				(hide yes)
			)
		)
	)
	(global_label "VDDQ"
		(shape input)
		(at 112.395 45.72 180)
		(fields_autoplaced yes)
		(effects
			(font
				(size 1.27 1.27)
			)
			(justify right)
		)
		(property "Intersheetrefs" "${INTERSHEET_REFS}"
			(at 53.975 166.37 0)
			(effects
				(font
					(size 1.27 1.27)
				)
				(hide yes)
			)
		)
	)
	(global_label "DQ03_A"
		(shape input)
		(at 246.38 78.74 0)
		(fields_autoplaced yes)
		(effects
			(font
				(size 1.27 1.27)
			)
			(justify left)
		)
		(property "Intersheetrefs" "${INTERSHEET_REFS}"
			(at 336.55 -41.91 0)
			(effects
				(font
					(size 1.27 1.27)
				)
				(justify left)
				(hide yes)
			)
		)
	)
	(global_label "CS0_B"
		(shape input)
		(at 185.42 186.69 180)
		(fields_autoplaced yes)
		(effects
			(font
				(size 1.27 1.27)
			)
			(justify right)
		)
		(property "Intersheetrefs" "${INTERSHEET_REFS}"
			(at -52.07 109.22 0)
			(effects
				(font
					(size 1.27 1.27)
				)
				(hide yes)
			)
		)
	)
	(symbol
		(lib_id "antmicroResistors0402:R_10k_0402")
		(at 189.23 187.325 270)
		(unit 1)
		(exclude_from_sim no)
		(in_bom yes)
		(on_board yes)
		(dnp no)
		(fields_autoplaced yes)
		(property "Reference" "R3"
			(at 191.77 188.5949 90)
			(effects
				(font
					(size 1.27 1.27)
					(thickness 0.15)
				)
				(justify left)
			)
		)
		(property "Value" "R_10k_0402"
			(at 185.42 187.325 0)
			(effects
				(font
					(size 1.27 1.27)
					(thickness 0.15)
				)
				(justify left bottom)
				(hide yes)
			)
		)
		(property "Footprint" "antmicro-footprints:R_0402_1005Metric"
			(at 194.31 192.405 0)
			(effects
				(font
					(size 1.27 1.27)
					(thickness 0.15)
				)
				(justify left bottom)
				(hide yes)
			)
		)
		(property "Datasheet" ""
			(at 189.23 187.325 0)
			(effects
				(font
					(size 1.27 1.27)
					(thickness 0.15)
				)
				(justify left bottom)
				(hide yes)
			)
		)
		(property "Description" ""
			(at 189.23 187.325 0)
			(effects
				(font
					(size 1.27 1.27)
				)
			)
		)
		(property "Manufacturer" "VISHAY"
			(at 199.39 192.405 0)
			(effects
				(font
					(size 1.27 1.27)
					(thickness 0.15)
				)
				(justify left bottom)
				(hide yes)
			)
		)
		(property "MPN" "CRCW040210K0FKEDHP"
			(at 196.85 192.405 0)
			(effects
				(font
					(size 1.27 1.27)
					(thickness 0.15)
				)
				(justify left bottom)
				(hide yes)
			)
		)
		(property "Val" "10k"
			(at 191.77 191.1349 90)
			(effects
				(font
					(size 1.27 1.27)
					(thickness 0.15)
				)
				(justify left)
			)
		)
		(property "License" "Apache-2.0"
			(at 163.83 207.645 0)
			(effects
				(font
					(size 1.27 1.27)
					(thickness 0.15)
				)
				(justify left bottom)
				(hide yes)
			)
		)
		(property "Author" "Antmicro"
			(at 161.29 207.645 0)
			(effects
				(font
					(size 1.27 1.27)
					(thickness 0.15)
				)
				(justify left bottom)
				(hide yes)
			)
		)
		(property "Tolerance" "1%"
			(at 179.07 207.645 0)
			(effects
				(font
					(size 1.27 1.27)
				)
				(justify left bottom)
				(hide yes)
			)
		)
		(pin "1"
		)
		(pin "2"
		)
		(instances
			(project "lpddr4-testbed"
				(path ""
					(reference "R3")
					(unit 1)
				)
			)
		)
	)
	(symbol
		(lib_id "antmicropower:GND")
		(at 189.23 193.04 0)
		(unit 1)
		(exclude_from_sim no)
		(in_bom yes)
		(on_board yes)
		(dnp no)
		(property "Reference" "#PWR038"
			(at 189.23 199.39 0)
			(effects
				(font
					(size 1.27 1.27)
				)
				(hide yes)
			)
		)
		(property "Value" "GND"
			(at 189.357 197.4342 0)
			(effects
				(font
					(size 1.27 1.27)
				)
			)
		)
		(property "Footprint" ""
			(at 189.23 193.04 0)
			(effects
				(font
					(size 1.27 1.27)
				)
				(hide yes)
			)
		)
		(property "Datasheet" ""
			(at 189.23 193.04 0)
			(effects
				(font
					(size 1.27 1.27)
				)
				(hide yes)
			)
		)
		(property "Description" ""
			(at 189.23 193.04 0)
			(effects
				(font
					(size 1.27 1.27)
				)
			)
		)
		(pin "1"
		)
		(instances
			(project "lpddr4-testbed"
				(path ""
					(reference "#PWR038")
					(unit 1)
				)
			)
		)
	)
	(symbol
		(lib_id "antmicroResistors0402:R_10k_0402")
		(at 174.625 109.22 90)
		(mirror x)
		(unit 1)
		(exclude_from_sim no)
		(in_bom yes)
		(on_board yes)
		(dnp no)
		(property "Reference" "R1"
			(at 175.895 110.49 90)
			(effects
				(font
					(size 1.27 1.27)
					(thickness 0.15)
				)
				(justify right)
			)
		)
		(property "Value" "R_10k_0402"
			(at 178.435 109.22 0)
			(effects
				(font
					(size 1.27 1.27)
					(thickness 0.15)
				)
				(justify left bottom)
				(hide yes)
			)
		)
		(property "Footprint" "antmicro-footprints:R_0402_1005Metric"
			(at 169.545 114.3 0)
			(effects
				(font
					(size 1.27 1.27)
					(thickness 0.15)
				)
				(justify left bottom)
				(hide yes)
			)
		)
		(property "Datasheet" ""
			(at 174.625 109.22 0)
			(effects
				(font
					(size 1.27 1.27)
					(thickness 0.15)
				)
				(justify left bottom)
				(hide yes)
			)
		)
		(property "Description" ""
			(at 174.625 109.22 0)
			(effects
				(font
					(size 1.27 1.27)
				)
			)
		)
		(property "Manufacturer" "VISHAY"
			(at 164.465 114.3 0)
			(effects
				(font
					(size 1.27 1.27)
					(thickness 0.15)
				)
				(justify left bottom)
				(hide yes)
			)
		)
		(property "MPN" "CRCW040210K0FKEDHP"
			(at 167.005 114.3 0)
			(effects
				(font
					(size 1.27 1.27)
					(thickness 0.15)
				)
				(justify left bottom)
				(hide yes)
			)
		)
		(property "Val" "10k"
			(at 175.895 113.03 90)
			(effects
				(font
					(size 1.27 1.27)
					(thickness 0.15)
				)
				(justify right)
			)
		)
		(property "License" "Apache-2.0"
			(at 200.025 129.54 0)
			(effects
				(font
					(size 1.27 1.27)
					(thickness 0.15)
				)
				(justify left bottom)
				(hide yes)
			)
		)
		(property "Author" "Antmicro"
			(at 202.565 129.54 0)
			(effects
				(font
					(size 1.27 1.27)
					(thickness 0.15)
				)
				(justify left bottom)
				(hide yes)
			)
		)
		(property "Tolerance" "1%"
			(at 184.785 129.54 0)
			(effects
				(font
					(size 1.27 1.27)
				)
				(justify left bottom)
				(hide yes)
			)
		)
		(pin "1"
		)
		(pin "2"
		)
		(instances
			(project "lpddr4-testbed"
				(path ""
					(reference "R1")
					(unit 1)
				)
			)
		)
	)
	(symbol
		(lib_id "antmicroCapacitorsmisc:C_100n_0201")
		(at 114.3 52.07 90)
		(unit 1)
		(exclude_from_sim no)
		(in_bom yes)
		(on_board yes)
		(dnp no)
		(property "Reference" "C1"
			(at 114.935 47.625 90)
			(effects
				(font
					(size 1.27 1.27)
					(thickness 0.15)
				)
				(justify right)
			)
		)
		(property "Value" "C_100n_0201"
			(at 118.11 52.07 0)
			(effects
				(font
					(size 1.27 1.27)
					(thickness 0.15)
				)
				(justify left bottom)
				(hide yes)
			)
		)
		(property "Footprint" "antmicro-footprints:C_0201"
			(at 109.22 46.99 0)
			(effects
				(font
					(size 1.27 1.27)
					(thickness 0.15)
				)
				(justify left bottom)
				(hide yes)
			)
		)
		(property "Datasheet" ""
			(at 114.3 52.07 0)
			(effects
				(font
					(size 1.27 1.27)
					(thickness 0.15)
				)
				(justify left bottom)
				(hide yes)
			)
		)
		(property "Description" ""
			(at 114.3 52.07 0)
			(effects
				(font
					(size 1.27 1.27)
				)
			)
		)
		(property "Manufacturer" "YAGEO"
			(at 104.14 46.99 0)
			(effects
				(font
					(size 1.27 1.27)
					(thickness 0.15)
				)
				(justify left bottom)
				(hide yes)
			)
		)
		(property "MPN" "CC0201KRX6S5BB104"
			(at 106.68 46.99 0)
			(effects
				(font
					(size 1.27 1.27)
					(thickness 0.15)
				)
				(justify left bottom)
				(hide yes)
			)
		)
		(property "Val" "100n"
			(at 114.935 51.435 90)
			(effects
				(font
					(size 1.27 1.27)
					(thickness 0.15)
				)
				(justify right)
			)
		)
		(property "License" "Apache-2.0"
			(at 137.16 31.75 0)
			(effects
				(font
					(size 1.27 1.27)
					(thickness 0.15)
				)
				(justify left bottom)
				(hide yes)
			)
		)
		(property "Author" "Antmicro"
			(at 139.7 31.75 0)
			(effects
				(font
					(size 1.27 1.27)
					(thickness 0.15)
				)
				(justify left bottom)
				(hide yes)
			)
		)
		(property "Voltage" ""
			(at 142.24 31.75 0)
			(effects
				(font
					(size 1.27 1.27)
				)
				(justify left bottom)
				(hide yes)
			)
		)
		(property "Dielectric" ""
			(at 144.78 31.75 0)
			(effects
				(font
					(size 1.27 1.27)
				)
				(justify left bottom)
				(hide yes)
			)
		)
		(pin "1"
		)
		(pin "2"
		)
		(instances
			(project "lpddr4-testbed"
				(path ""
					(reference "C1")
					(unit 1)
				)
			)
		)
	)
	(symbol
		(lib_id "antmicroResistors0402:R_0R_0402")
		(at 169.545 116.84 0)
		(mirror y)
		(unit 1)
		(exclude_from_sim no)
		(in_bom yes)
		(on_board yes)
		(dnp no)
		(property "Reference" "R2"
			(at 170.815 115.57 0)
			(effects
				(font
					(size 1.27 1.27)
					(thickness 0.15)
				)
			)
		)
		(property "Value" "R_0R_0402"
			(at 169.545 120.65 0)
			(effects
				(font
					(size 1.27 1.27)
					(thickness 0.15)
				)
				(justify left bottom)
				(hide yes)
			)
		)
		(property "Footprint" "antmicro-footprints:R_0402_1005Metric"
			(at 164.465 111.76 0)
			(effects
				(font
					(size 1.27 1.27)
					(thickness 0.15)
				)
				(justify left bottom)
				(hide yes)
			)
		)
		(property "Datasheet" ""
			(at 169.545 116.84 0)
			(effects
				(font
					(size 1.27 1.27)
					(thickness 0.15)
				)
				(justify left bottom)
				(hide yes)
			)
		)
		(property "Description" ""
			(at 169.545 116.84 0)
			(effects
				(font
					(size 1.27 1.27)
				)
			)
		)
		(property "Manufacturer" "PANASONIC"
			(at 164.465 106.68 0)
			(effects
				(font
					(size 1.27 1.27)
					(thickness 0.15)
				)
				(justify left bottom)
				(hide yes)
			)
		)
		(property "MPN" "ERJ2GE0R00X"
			(at 164.465 109.22 0)
			(effects
				(font
					(size 1.27 1.27)
					(thickness 0.15)
				)
				(justify left bottom)
				(hide yes)
			)
		)
		(property "Val" "0R"
			(at 163.195 115.57 0)
			(effects
				(font
					(size 1.27 1.27)
					(thickness 0.15)
				)
			)
		)
		(property "License" "Apache-2.0"
			(at 149.225 142.24 0)
			(effects
				(font
					(size 1.27 1.27)
					(thickness 0.15)
				)
				(justify left bottom)
				(hide yes)
			)
		)
		(property "Author" "Antmicro"
			(at 149.225 144.78 0)
			(effects
				(font
					(size 1.27 1.27)
					(thickness 0.15)
				)
				(justify left bottom)
				(hide yes)
			)
		)
		(property "Tolerance" "~"
			(at 149.225 127 0)
			(effects
				(font
					(size 1.27 1.27)
				)
				(justify left bottom)
				(hide yes)
			)
		)
		(property "Current" "1A"
			(at 149.225 147.32 0)
			(effects
				(font
					(size 1.27 1.27)
					(thickness 0.15)
				)
				(justify left bottom)
				(hide yes)
			)
		)
		(pin "1"
		)
		(pin "2"
		)
		(instances
			(project "lpddr4-testbed"
				(path ""
					(reference "R2")
					(unit 1)
				)
			)
		)
	)
	(symbol
		(lib_id "antmicroCapacitorsmisc:C_100n_0201")
		(at 128.27 52.07 90)
		(unit 1)
		(exclude_from_sim no)
		(in_bom yes)
		(on_board yes)
		(dnp no)
		(property "Reference" "C4"
			(at 128.905 47.625 90)
			(effects
				(font
					(size 1.27 1.27)
					(thickness 0.15)
				)
				(justify right)
			)
		)
		(property "Value" "C_100n_0201"
			(at 132.08 52.07 0)
			(effects
				(font
					(size 1.27 1.27)
					(thickness 0.15)
				)
				(justify left bottom)
				(hide yes)
			)
		)
		(property "Footprint" "antmicro-footprints:C_0201"
			(at 123.19 46.99 0)
			(effects
				(font
					(size 1.27 1.27)
					(thickness 0.15)
				)
				(justify left bottom)
				(hide yes)
			)
		)
		(property "Datasheet" ""
			(at 128.27 52.07 0)
			(effects
				(font
					(size 1.27 1.27)
					(thickness 0.15)
				)
				(justify left bottom)
				(hide yes)
			)
		)
		(property "Description" ""
			(at 128.27 52.07 0)
			(effects
				(font
					(size 1.27 1.27)
				)
			)
		)
		(property "Manufacturer" "YAGEO"
			(at 118.11 46.99 0)
			(effects
				(font
					(size 1.27 1.27)
					(thickness 0.15)
				)
				(justify left bottom)
				(hide yes)
			)
		)
		(property "MPN" "CC0201KRX6S5BB104"
			(at 120.65 46.99 0)
			(effects
				(font
					(size 1.27 1.27)
					(thickness 0.15)
				)
				(justify left bottom)
				(hide yes)
			)
		)
		(property "Val" "100n"
			(at 128.905 51.435 90)
			(effects
				(font
					(size 1.27 1.27)
					(thickness 0.15)
				)
				(justify right)
			)
		)
		(property "License" "Apache-2.0"
			(at 151.13 31.75 0)
			(effects
				(font
					(size 1.27 1.27)
					(thickness 0.15)
				)
				(justify left bottom)
				(hide yes)
			)
		)
		(property "Author" "Antmicro"
			(at 153.67 31.75 0)
			(effects
				(font
					(size 1.27 1.27)
					(thickness 0.15)
				)
				(justify left bottom)
				(hide yes)
			)
		)
		(property "Voltage" ""
			(at 156.21 31.75 0)
			(effects
				(font
					(size 1.27 1.27)
				)
				(justify left bottom)
				(hide yes)
			)
		)
		(property "Dielectric" ""
			(at 158.75 31.75 0)
			(effects
				(font
					(size 1.27 1.27)
				)
				(justify left bottom)
				(hide yes)
			)
		)
		(pin "1"
		)
		(pin "2"
		)
		(instances
			(project "lpddr4-testbed"
				(path ""
					(reference "C4")
					(unit 1)
				)
			)
		)
	)
	(symbol
		(lib_id "antmicroCapacitorsmisc:C_100n_0201")
		(at 142.24 52.07 90)
		(unit 1)
		(exclude_from_sim no)
		(in_bom yes)
		(on_board yes)
		(dnp no)
		(property "Reference" "C7"
			(at 142.875 47.625 90)
			(effects
				(font
					(size 1.27 1.27)
					(thickness 0.15)
				)
				(justify right)
			)
		)
		(property "Value" "C_100n_0201"
			(at 146.05 52.07 0)
			(effects
				(font
					(size 1.27 1.27)
					(thickness 0.15)
				)
				(justify left bottom)
				(hide yes)
			)
		)
		(property "Footprint" "antmicro-footprints:C_0201"
			(at 137.16 46.99 0)
			(effects
				(font
					(size 1.27 1.27)
					(thickness 0.15)
				)
				(justify left bottom)
				(hide yes)
			)
		)
		(property "Datasheet" ""
			(at 142.24 52.07 0)
			(effects
				(font
					(size 1.27 1.27)
					(thickness 0.15)
				)
				(justify left bottom)
				(hide yes)
			)
		)
		(property "Description" ""
			(at 142.24 52.07 0)
			(effects
				(font
					(size 1.27 1.27)
				)
			)
		)
		(property "Manufacturer" "YAGEO"
			(at 132.08 46.99 0)
			(effects
				(font
					(size 1.27 1.27)
					(thickness 0.15)
				)
				(justify left bottom)
				(hide yes)
			)
		)
		(property "MPN" "CC0201KRX6S5BB104"
			(at 134.62 46.99 0)
			(effects
				(font
					(size 1.27 1.27)
					(thickness 0.15)
				)
				(justify left bottom)
				(hide yes)
			)
		)
		(property "Val" "100n"
			(at 143.51 51.435 90)
			(effects
				(font
					(size 1.27 1.27)
					(thickness 0.15)
				)
				(justify right)
			)
		)
		(property "License" "Apache-2.0"
			(at 165.1 31.75 0)
			(effects
				(font
					(size 1.27 1.27)
					(thickness 0.15)
				)
				(justify left bottom)
				(hide yes)
			)
		)
		(property "Author" "Antmicro"
			(at 167.64 31.75 0)
			(effects
				(font
					(size 1.27 1.27)
					(thickness 0.15)
				)
				(justify left bottom)
				(hide yes)
			)
		)
		(property "Voltage" ""
			(at 170.18 31.75 0)
			(effects
				(font
					(size 1.27 1.27)
				)
				(justify left bottom)
				(hide yes)
			)
		)
		(property "Dielectric" ""
			(at 172.72 31.75 0)
			(effects
				(font
					(size 1.27 1.27)
				)
				(justify left bottom)
				(hide yes)
			)
		)
		(pin "1"
		)
		(pin "2"
		)
		(instances
			(project "lpddr4-testbed"
				(path ""
					(reference "C7")
					(unit 1)
				)
			)
		)
	)
	(symbol
		(lib_id "antmicroCapacitorsmisc:C_100n_0201")
		(at 156.21 52.07 90)
		(unit 1)
		(exclude_from_sim no)
		(in_bom yes)
		(on_board yes)
		(dnp no)
		(property "Reference" "C10"
			(at 156.845 47.625 90)
			(effects
				(font
					(size 1.27 1.27)
					(thickness 0.15)
				)
				(justify right)
			)
		)
		(property "Value" "C_100n_0201"
			(at 160.02 52.07 0)
			(effects
				(font
					(size 1.27 1.27)
					(thickness 0.15)
				)
				(justify left bottom)
				(hide yes)
			)
		)
		(property "Footprint" "antmicro-footprints:C_0201"
			(at 151.13 46.99 0)
			(effects
				(font
					(size 1.27 1.27)
					(thickness 0.15)
				)
				(justify left bottom)
				(hide yes)
			)
		)
		(property "Datasheet" ""
			(at 156.21 52.07 0)
			(effects
				(font
					(size 1.27 1.27)
					(thickness 0.15)
				)
				(justify left bottom)
				(hide yes)
			)
		)
		(property "Description" ""
			(at 156.21 52.07 0)
			(effects
				(font
					(size 1.27 1.27)
				)
			)
		)
		(property "Manufacturer" "YAGEO"
			(at 146.05 46.99 0)
			(effects
				(font
					(size 1.27 1.27)
					(thickness 0.15)
				)
				(justify left bottom)
				(hide yes)
			)
		)
		(property "MPN" "CC0201KRX6S5BB104"
			(at 148.59 46.99 0)
			(effects
				(font
					(size 1.27 1.27)
					(thickness 0.15)
				)
				(justify left bottom)
				(hide yes)
			)
		)
		(property "Val" "100n"
			(at 156.845 51.435 90)
			(effects
				(font
					(size 1.27 1.27)
					(thickness 0.15)
				)
				(justify right)
			)
		)
		(property "License" "Apache-2.0"
			(at 179.07 31.75 0)
			(effects
				(font
					(size 1.27 1.27)
					(thickness 0.15)
				)
				(justify left bottom)
				(hide yes)
			)
		)
		(property "Author" "Antmicro"
			(at 181.61 31.75 0)
			(effects
				(font
					(size 1.27 1.27)
					(thickness 0.15)
				)
				(justify left bottom)
				(hide yes)
			)
		)
		(property "Voltage" ""
			(at 184.15 31.75 0)
			(effects
				(font
					(size 1.27 1.27)
				)
				(justify left bottom)
				(hide yes)
			)
		)
		(property "Dielectric" ""
			(at 186.69 31.75 0)
			(effects
				(font
					(size 1.27 1.27)
				)
				(justify left bottom)
				(hide yes)
			)
		)
		(pin "1"
		)
		(pin "2"
		)
		(instances
			(project "lpddr4-testbed"
				(path ""
					(reference "C10")
					(unit 1)
				)
			)
		)
	)
	(symbol
		(lib_id "antmicroCapacitorsmisc:C_100n_0201")
		(at 121.285 152.4 90)
		(unit 1)
		(exclude_from_sim no)
		(in_bom yes)
		(on_board yes)
		(dnp no)
		(property "Reference" "C13"
			(at 121.92 147.955 90)
			(effects
				(font
					(size 1.27 1.27)
					(thickness 0.15)
				)
				(justify right)
			)
		)
		(property "Value" "C_100n_0201"
			(at 125.095 152.4 0)
			(effects
				(font
					(size 1.27 1.27)
					(thickness 0.15)
				)
				(justify left bottom)
				(hide yes)
			)
		)
		(property "Footprint" "antmicro-footprints:C_0201"
			(at 116.205 147.32 0)
			(effects
				(font
					(size 1.27 1.27)
					(thickness 0.15)
				)
				(justify left bottom)
				(hide yes)
			)
		)
		(property "Datasheet" ""
			(at 121.285 152.4 0)
			(effects
				(font
					(size 1.27 1.27)
					(thickness 0.15)
				)
				(justify left bottom)
				(hide yes)
			)
		)
		(property "Description" ""
			(at 121.285 152.4 0)
			(effects
				(font
					(size 1.27 1.27)
				)
			)
		)
		(property "Manufacturer" "YAGEO"
			(at 111.125 147.32 0)
			(effects
				(font
					(size 1.27 1.27)
					(thickness 0.15)
				)
				(justify left bottom)
				(hide yes)
			)
		)
		(property "MPN" "CC0201KRX6S5BB104"
			(at 113.665 147.32 0)
			(effects
				(font
					(size 1.27 1.27)
					(thickness 0.15)
				)
				(justify left bottom)
				(hide yes)
			)
		)
		(property "Val" "100n"
			(at 121.92 151.765 90)
			(effects
				(font
					(size 1.27 1.27)
					(thickness 0.15)
				)
				(justify right)
			)
		)
		(property "License" "Apache-2.0"
			(at 144.145 132.08 0)
			(effects
				(font
					(size 1.27 1.27)
					(thickness 0.15)
				)
				(justify left bottom)
				(hide yes)
			)
		)
		(property "Author" "Antmicro"
			(at 146.685 132.08 0)
			(effects
				(font
					(size 1.27 1.27)
					(thickness 0.15)
				)
				(justify left bottom)
				(hide yes)
			)
		)
		(property "Voltage" ""
			(at 149.225 132.08 0)
			(effects
				(font
					(size 1.27 1.27)
				)
				(justify left bottom)
				(hide yes)
			)
		)
		(property "Dielectric" ""
			(at 151.765 132.08 0)
			(effects
				(font
					(size 1.27 1.27)
				)
				(justify left bottom)
				(hide yes)
			)
		)
		(pin "1"
		)
		(pin "2"
		)
		(instances
			(project "lpddr4-testbed"
				(path ""
					(reference "C13")
					(unit 1)
				)
			)
		)
	)
	(symbol
		(lib_id "antmicroCapacitorsmisc:C_100n_0201")
		(at 135.255 152.4 90)
		(unit 1)
		(exclude_from_sim no)
		(in_bom yes)
		(on_board yes)
		(dnp no)
		(property "Reference" "C16"
			(at 135.89 147.955 90)
			(effects
				(font
					(size 1.27 1.27)
					(thickness 0.15)
				)
				(justify right)
			)
		)
		(property "Value" "C_100n_0201"
			(at 139.065 152.4 0)
			(effects
				(font
					(size 1.27 1.27)
					(thickness 0.15)
				)
				(justify left bottom)
				(hide yes)
			)
		)
		(property "Footprint" "antmicro-footprints:C_0201"
			(at 130.175 147.32 0)
			(effects
				(font
					(size 1.27 1.27)
					(thickness 0.15)
				)
				(justify left bottom)
				(hide yes)
			)
		)
		(property "Datasheet" ""
			(at 135.255 152.4 0)
			(effects
				(font
					(size 1.27 1.27)
					(thickness 0.15)
				)
				(justify left bottom)
				(hide yes)
			)
		)
		(property "Description" ""
			(at 135.255 152.4 0)
			(effects
				(font
					(size 1.27 1.27)
				)
			)
		)
		(property "Manufacturer" "YAGEO"
			(at 125.095 147.32 0)
			(effects
				(font
					(size 1.27 1.27)
					(thickness 0.15)
				)
				(justify left bottom)
				(hide yes)
			)
		)
		(property "MPN" "CC0201KRX6S5BB104"
			(at 127.635 147.32 0)
			(effects
				(font
					(size 1.27 1.27)
					(thickness 0.15)
				)
				(justify left bottom)
				(hide yes)
			)
		)
		(property "Val" "100n"
			(at 135.89 151.765 90)
			(effects
				(font
					(size 1.27 1.27)
					(thickness 0.15)
				)
				(justify right)
			)
		)
		(property "License" "Apache-2.0"
			(at 158.115 132.08 0)
			(effects
				(font
					(size 1.27 1.27)
					(thickness 0.15)
				)
				(justify left bottom)
				(hide yes)
			)
		)
		(property "Author" "Antmicro"
			(at 160.655 132.08 0)
			(effects
				(font
					(size 1.27 1.27)
					(thickness 0.15)
				)
				(justify left bottom)
				(hide yes)
			)
		)
		(property "Voltage" ""
			(at 163.195 132.08 0)
			(effects
				(font
					(size 1.27 1.27)
				)
				(justify left bottom)
				(hide yes)
			)
		)
		(property "Dielectric" ""
			(at 165.735 132.08 0)
			(effects
				(font
					(size 1.27 1.27)
				)
				(justify left bottom)
				(hide yes)
			)
		)
		(pin "1"
		)
		(pin "2"
		)
		(instances
			(project "lpddr4-testbed"
				(path ""
					(reference "C16")
					(unit 1)
				)
			)
		)
	)
	(symbol
		(lib_id "antmicroCapacitorsmisc:C_100n_0201")
		(at 149.225 152.4 90)
		(unit 1)
		(exclude_from_sim no)
		(in_bom yes)
		(on_board yes)
		(dnp no)
		(property "Reference" "C19"
			(at 149.86 147.955 90)
			(effects
				(font
					(size 1.27 1.27)
					(thickness 0.15)
				)
				(justify right)
			)
		)
		(property "Value" "C_100n_0201"
			(at 153.035 152.4 0)
			(effects
				(font
					(size 1.27 1.27)
					(thickness 0.15)
				)
				(justify left bottom)
				(hide yes)
			)
		)
		(property "Footprint" "antmicro-footprints:C_0201"
			(at 144.145 147.32 0)
			(effects
				(font
					(size 1.27 1.27)
					(thickness 0.15)
				)
				(justify left bottom)
				(hide yes)
			)
		)
		(property "Datasheet" ""
			(at 149.225 152.4 0)
			(effects
				(font
					(size 1.27 1.27)
					(thickness 0.15)
				)
				(justify left bottom)
				(hide yes)
			)
		)
		(property "Description" ""
			(at 149.225 152.4 0)
			(effects
				(font
					(size 1.27 1.27)
				)
			)
		)
		(property "Manufacturer" "YAGEO"
			(at 139.065 147.32 0)
			(effects
				(font
					(size 1.27 1.27)
					(thickness 0.15)
				)
				(justify left bottom)
				(hide yes)
			)
		)
		(property "MPN" "CC0201KRX6S5BB104"
			(at 141.605 147.32 0)
			(effects
				(font
					(size 1.27 1.27)
					(thickness 0.15)
				)
				(justify left bottom)
				(hide yes)
			)
		)
		(property "Val" "100n"
			(at 150.495 151.765 90)
			(effects
				(font
					(size 1.27 1.27)
					(thickness 0.15)
				)
				(justify right)
			)
		)
		(property "License" "Apache-2.0"
			(at 172.085 132.08 0)
			(effects
				(font
					(size 1.27 1.27)
					(thickness 0.15)
				)
				(justify left bottom)
				(hide yes)
			)
		)
		(property "Author" "Antmicro"
			(at 174.625 132.08 0)
			(effects
				(font
					(size 1.27 1.27)
					(thickness 0.15)
				)
				(justify left bottom)
				(hide yes)
			)
		)
		(property "Voltage" ""
			(at 177.165 132.08 0)
			(effects
				(font
					(size 1.27 1.27)
				)
				(justify left bottom)
				(hide yes)
			)
		)
		(property "Dielectric" ""
			(at 179.705 132.08 0)
			(effects
				(font
					(size 1.27 1.27)
				)
				(justify left bottom)
				(hide yes)
			)
		)
		(pin "1"
		)
		(pin "2"
		)
		(instances
			(project "lpddr4-testbed"
				(path ""
					(reference "C19")
					(unit 1)
				)
			)
		)
	)
	(symbol
		(lib_id "antmicroCapacitorsmisc:C_100n_0201")
		(at 156.21 152.4 90)
		(unit 1)
		(exclude_from_sim no)
		(in_bom yes)
		(on_board yes)
		(dnp no)
		(property "Reference" "C21"
			(at 156.845 147.955 90)
			(effects
				(font
					(size 1.27 1.27)
					(thickness 0.15)
				)
				(justify right)
			)
		)
		(property "Value" "C_100n_0201"
			(at 160.02 152.4 0)
			(effects
				(font
					(size 1.27 1.27)
					(thickness 0.15)
				)
				(justify left bottom)
				(hide yes)
			)
		)
		(property "Footprint" "antmicro-footprints:C_0201"
			(at 151.13 147.32 0)
			(effects
				(font
					(size 1.27 1.27)
					(thickness 0.15)
				)
				(justify left bottom)
				(hide yes)
			)
		)
		(property "Datasheet" ""
			(at 156.21 152.4 0)
			(effects
				(font
					(size 1.27 1.27)
					(thickness 0.15)
				)
				(justify left bottom)
				(hide yes)
			)
		)
		(property "Description" ""
			(at 156.21 152.4 0)
			(effects
				(font
					(size 1.27 1.27)
				)
			)
		)
		(property "Manufacturer" "YAGEO"
			(at 146.05 147.32 0)
			(effects
				(font
					(size 1.27 1.27)
					(thickness 0.15)
				)
				(justify left bottom)
				(hide yes)
			)
		)
		(property "MPN" "CC0201KRX6S5BB104"
			(at 148.59 147.32 0)
			(effects
				(font
					(size 1.27 1.27)
					(thickness 0.15)
				)
				(justify left bottom)
				(hide yes)
			)
		)
		(property "Val" "100n"
			(at 156.845 151.765 90)
			(effects
				(font
					(size 1.27 1.27)
					(thickness 0.15)
				)
				(justify right)
			)
		)
		(property "License" "Apache-2.0"
			(at 179.07 132.08 0)
			(effects
				(font
					(size 1.27 1.27)
					(thickness 0.15)
				)
				(justify left bottom)
				(hide yes)
			)
		)
		(property "Author" "Antmicro"
			(at 181.61 132.08 0)
			(effects
				(font
					(size 1.27 1.27)
					(thickness 0.15)
				)
				(justify left bottom)
				(hide yes)
			)
		)
		(property "Voltage" ""
			(at 184.15 132.08 0)
			(effects
				(font
					(size 1.27 1.27)
				)
				(justify left bottom)
				(hide yes)
			)
		)
		(property "Dielectric" ""
			(at 186.69 132.08 0)
			(effects
				(font
					(size 1.27 1.27)
				)
				(justify left bottom)
				(hide yes)
			)
		)
		(pin "1"
		)
		(pin "2"
		)
		(instances
			(project "lpddr4-testbed"
				(path ""
					(reference "C21")
					(unit 1)
				)
			)
		)
	)
	(symbol
		(lib_id "antmicroCapacitorsmisc:C_100n_0201")
		(at 121.285 52.07 90)
		(unit 1)
		(exclude_from_sim no)
		(in_bom yes)
		(on_board yes)
		(dnp no)
		(property "Reference" "C2"
			(at 121.92 47.625 90)
			(effects
				(font
					(size 1.27 1.27)
					(thickness 0.15)
				)
				(justify right)
			)
		)
		(property "Value" "C_100n_0201"
			(at 125.095 52.07 0)
			(effects
				(font
					(size 1.27 1.27)
					(thickness 0.15)
				)
				(justify left bottom)
				(hide yes)
			)
		)
		(property "Footprint" "antmicro-footprints:C_0201"
			(at 116.205 46.99 0)
			(effects
				(font
					(size 1.27 1.27)
					(thickness 0.15)
				)
				(justify left bottom)
				(hide yes)
			)
		)
		(property "Datasheet" ""
			(at 121.285 52.07 0)
			(effects
				(font
					(size 1.27 1.27)
					(thickness 0.15)
				)
				(justify left bottom)
				(hide yes)
			)
		)
		(property "Description" ""
			(at 121.285 52.07 0)
			(effects
				(font
					(size 1.27 1.27)
				)
			)
		)
		(property "Manufacturer" "YAGEO"
			(at 111.125 46.99 0)
			(effects
				(font
					(size 1.27 1.27)
					(thickness 0.15)
				)
				(justify left bottom)
				(hide yes)
			)
		)
		(property "MPN" "CC0201KRX6S5BB104"
			(at 113.665 46.99 0)
			(effects
				(font
					(size 1.27 1.27)
					(thickness 0.15)
				)
				(justify left bottom)
				(hide yes)
			)
		)
		(property "Val" "100n"
			(at 121.92 51.435 90)
			(effects
				(font
					(size 1.27 1.27)
					(thickness 0.15)
				)
				(justify right)
			)
		)
		(property "License" "Apache-2.0"
			(at 144.145 31.75 0)
			(effects
				(font
					(size 1.27 1.27)
					(thickness 0.15)
				)
				(justify left bottom)
				(hide yes)
			)
		)
		(property "Author" "Antmicro"
			(at 146.685 31.75 0)
			(effects
				(font
					(size 1.27 1.27)
					(thickness 0.15)
				)
				(justify left bottom)
				(hide yes)
			)
		)
		(property "Voltage" ""
			(at 149.225 31.75 0)
			(effects
				(font
					(size 1.27 1.27)
				)
				(justify left bottom)
				(hide yes)
			)
		)
		(property "Dielectric" ""
			(at 151.765 31.75 0)
			(effects
				(font
					(size 1.27 1.27)
				)
				(justify left bottom)
				(hide yes)
			)
		)
		(pin "1"
		)
		(pin "2"
		)
		(instances
			(project "lpddr4-testbed"
				(path ""
					(reference "C2")
					(unit 1)
				)
			)
		)
	)
	(symbol
		(lib_id "antmicropower:GND")
		(at 114.3 52.705 0)
		(unit 1)
		(exclude_from_sim no)
		(in_bom yes)
		(on_board yes)
		(dnp no)
		(property "Reference" "#PWR02"
			(at 114.3 59.055 0)
			(effects
				(font
					(size 1.27 1.27)
				)
				(hide yes)
			)
		)
		(property "Value" "GND"
			(at 114.427 57.0992 0)
			(effects
				(font
					(size 1.27 1.27)
				)
			)
		)
		(property "Footprint" ""
			(at 114.3 52.705 0)
			(effects
				(font
					(size 1.27 1.27)
				)
				(hide yes)
			)
		)
		(property "Datasheet" ""
			(at 114.3 52.705 0)
			(effects
				(font
					(size 1.27 1.27)
				)
				(hide yes)
			)
		)
		(property "Description" ""
			(at 114.3 52.705 0)
			(effects
				(font
					(size 1.27 1.27)
				)
			)
		)
		(pin "1"
		)
		(instances
			(project "lpddr4-testbed"
				(path ""
					(reference "#PWR02")
					(unit 1)
				)
			)
		)
	)
	(symbol
		(lib_id "antmicroCapacitorsmisc:C_100n_0201")
		(at 135.255 52.07 90)
		(unit 1)
		(exclude_from_sim no)
		(in_bom yes)
		(on_board yes)
		(dnp no)
		(property "Reference" "C5"
			(at 135.89 47.625 90)
			(effects
				(font
					(size 1.27 1.27)
					(thickness 0.15)
				)
				(justify right)
			)
		)
		(property "Value" "C_100n_0201"
			(at 139.065 52.07 0)
			(effects
				(font
					(size 1.27 1.27)
					(thickness 0.15)
				)
				(justify left bottom)
				(hide yes)
			)
		)
		(property "Footprint" "antmicro-footprints:C_0201"
			(at 130.175 46.99 0)
			(effects
				(font
					(size 1.27 1.27)
					(thickness 0.15)
				)
				(justify left bottom)
				(hide yes)
			)
		)
		(property "Datasheet" ""
			(at 135.255 52.07 0)
			(effects
				(font
					(size 1.27 1.27)
					(thickness 0.15)
				)
				(justify left bottom)
				(hide yes)
			)
		)
		(property "Description" ""
			(at 135.255 52.07 0)
			(effects
				(font
					(size 1.27 1.27)
				)
			)
		)
		(property "Manufacturer" "YAGEO"
			(at 125.095 46.99 0)
			(effects
				(font
					(size 1.27 1.27)
					(thickness 0.15)
				)
				(justify left bottom)
				(hide yes)
			)
		)
		(property "MPN" "CC0201KRX6S5BB104"
			(at 127.635 46.99 0)
			(effects
				(font
					(size 1.27 1.27)
					(thickness 0.15)
				)
				(justify left bottom)
				(hide yes)
			)
		)
		(property "Val" "100n"
			(at 135.89 51.435 90)
			(effects
				(font
					(size 1.27 1.27)
					(thickness 0.15)
				)
				(justify right)
			)
		)
		(property "License" "Apache-2.0"
			(at 158.115 31.75 0)
			(effects
				(font
					(size 1.27 1.27)
					(thickness 0.15)
				)
				(justify left bottom)
				(hide yes)
			)
		)
		(property "Author" "Antmicro"
			(at 160.655 31.75 0)
			(effects
				(font
					(size 1.27 1.27)
					(thickness 0.15)
				)
				(justify left bottom)
				(hide yes)
			)
		)
		(property "Voltage" ""
			(at 163.195 31.75 0)
			(effects
				(font
					(size 1.27 1.27)
				)
				(justify left bottom)
				(hide yes)
			)
		)
		(property "Dielectric" ""
			(at 165.735 31.75 0)
			(effects
				(font
					(size 1.27 1.27)
				)
				(justify left bottom)
				(hide yes)
			)
		)
		(pin "1"
		)
		(pin "2"
		)
		(instances
			(project "lpddr4-testbed"
				(path ""
					(reference "C5")
					(unit 1)
				)
			)
		)
	)
	(symbol
		(lib_id "antmicroCapacitorsmisc:C_100n_0201")
		(at 149.225 52.07 90)
		(unit 1)
		(exclude_from_sim no)
		(in_bom yes)
		(on_board yes)
		(dnp no)
		(property "Reference" "C8"
			(at 149.86 47.625 90)
			(effects
				(font
					(size 1.27 1.27)
					(thickness 0.15)
				)
				(justify right)
			)
		)
		(property "Value" "C_100n_0201"
			(at 153.035 52.07 0)
			(effects
				(font
					(size 1.27 1.27)
					(thickness 0.15)
				)
				(justify left bottom)
				(hide yes)
			)
		)
		(property "Footprint" "antmicro-footprints:C_0201"
			(at 144.145 46.99 0)
			(effects
				(font
					(size 1.27 1.27)
					(thickness 0.15)
				)
				(justify left bottom)
				(hide yes)
			)
		)
		(property "Datasheet" ""
			(at 149.225 52.07 0)
			(effects
				(font
					(size 1.27 1.27)
					(thickness 0.15)
				)
				(justify left bottom)
				(hide yes)
			)
		)
		(property "Description" ""
			(at 149.225 52.07 0)
			(effects
				(font
					(size 1.27 1.27)
				)
			)
		)
		(property "Manufacturer" "YAGEO"
			(at 139.065 46.99 0)
			(effects
				(font
					(size 1.27 1.27)
					(thickness 0.15)
				)
				(justify left bottom)
				(hide yes)
			)
		)
		(property "MPN" "CC0201KRX6S5BB104"
			(at 141.605 46.99 0)
			(effects
				(font
					(size 1.27 1.27)
					(thickness 0.15)
				)
				(justify left bottom)
				(hide yes)
			)
		)
		(property "Val" "100n"
			(at 149.86 51.435 90)
			(effects
				(font
					(size 1.27 1.27)
					(thickness 0.15)
				)
				(justify right)
			)
		)
		(property "License" "Apache-2.0"
			(at 172.085 31.75 0)
			(effects
				(font
					(size 1.27 1.27)
					(thickness 0.15)
				)
				(justify left bottom)
				(hide yes)
			)
		)
		(property "Author" "Antmicro"
			(at 174.625 31.75 0)
			(effects
				(font
					(size 1.27 1.27)
					(thickness 0.15)
				)
				(justify left bottom)
				(hide yes)
			)
		)
		(property "Voltage" ""
			(at 177.165 31.75 0)
			(effects
				(font
					(size 1.27 1.27)
				)
				(justify left bottom)
				(hide yes)
			)
		)
		(property "Dielectric" ""
			(at 179.705 31.75 0)
			(effects
				(font
					(size 1.27 1.27)
				)
				(justify left bottom)
				(hide yes)
			)
		)
		(pin "1"
		)
		(pin "2"
		)
		(instances
			(project "lpddr4-testbed"
				(path ""
					(reference "C8")
					(unit 1)
				)
			)
		)
	)
	(symbol
		(lib_id "antmicroCapacitorsmisc:C_100n_0201")
		(at 114.3 152.4 90)
		(unit 1)
		(exclude_from_sim no)
		(in_bom yes)
		(on_board yes)
		(dnp no)
		(property "Reference" "C11"
			(at 114.935 147.955 90)
			(effects
				(font
					(size 1.27 1.27)
					(thickness 0.15)
				)
				(justify right)
			)
		)
		(property "Value" "C_100n_0201"
			(at 118.11 152.4 0)
			(effects
				(font
					(size 1.27 1.27)
					(thickness 0.15)
				)
				(justify left bottom)
				(hide yes)
			)
		)
		(property "Footprint" "antmicro-footprints:C_0201"
			(at 109.22 147.32 0)
			(effects
				(font
					(size 1.27 1.27)
					(thickness 0.15)
				)
				(justify left bottom)
				(hide yes)
			)
		)
		(property "Datasheet" ""
			(at 114.3 152.4 0)
			(effects
				(font
					(size 1.27 1.27)
					(thickness 0.15)
				)
				(justify left bottom)
				(hide yes)
			)
		)
		(property "Description" ""
			(at 114.3 152.4 0)
			(effects
				(font
					(size 1.27 1.27)
				)
			)
		)
		(property "Manufacturer" "YAGEO"
			(at 104.14 147.32 0)
			(effects
				(font
					(size 1.27 1.27)
					(thickness 0.15)
				)
				(justify left bottom)
				(hide yes)
			)
		)
		(property "MPN" "CC0201KRX6S5BB104"
			(at 106.68 147.32 0)
			(effects
				(font
					(size 1.27 1.27)
					(thickness 0.15)
				)
				(justify left bottom)
				(hide yes)
			)
		)
		(property "Val" "100n"
			(at 114.935 151.765 90)
			(effects
				(font
					(size 1.27 1.27)
					(thickness 0.15)
				)
				(justify right)
			)
		)
		(property "License" "Apache-2.0"
			(at 137.16 132.08 0)
			(effects
				(font
					(size 1.27 1.27)
					(thickness 0.15)
				)
				(justify left bottom)
				(hide yes)
			)
		)
		(property "Author" "Antmicro"
			(at 139.7 132.08 0)
			(effects
				(font
					(size 1.27 1.27)
					(thickness 0.15)
				)
				(justify left bottom)
				(hide yes)
			)
		)
		(property "Voltage" ""
			(at 142.24 132.08 0)
			(effects
				(font
					(size 1.27 1.27)
				)
				(justify left bottom)
				(hide yes)
			)
		)
		(property "Dielectric" ""
			(at 144.78 132.08 0)
			(effects
				(font
					(size 1.27 1.27)
				)
				(justify left bottom)
				(hide yes)
			)
		)
		(pin "1"
		)
		(pin "2"
		)
		(instances
			(project "lpddr4-testbed"
				(path ""
					(reference "C11")
					(unit 1)
				)
			)
		)
	)
	(symbol
		(lib_id "antmicroCapacitorsmisc:C_100n_0201")
		(at 128.27 152.4 90)
		(unit 1)
		(exclude_from_sim no)
		(in_bom yes)
		(on_board yes)
		(dnp no)
		(property "Reference" "C14"
			(at 128.905 147.955 90)
			(effects
				(font
					(size 1.27 1.27)
					(thickness 0.15)
				)
				(justify right)
			)
		)
		(property "Value" "C_100n_0201"
			(at 132.08 152.4 0)
			(effects
				(font
					(size 1.27 1.27)
					(thickness 0.15)
				)
				(justify left bottom)
				(hide yes)
			)
		)
		(property "Footprint" "antmicro-footprints:C_0201"
			(at 123.19 147.32 0)
			(effects
				(font
					(size 1.27 1.27)
					(thickness 0.15)
				)
				(justify left bottom)
				(hide yes)
			)
		)
		(property "Datasheet" ""
			(at 128.27 152.4 0)
			(effects
				(font
					(size 1.27 1.27)
					(thickness 0.15)
				)
				(justify left bottom)
				(hide yes)
			)
		)
		(property "Description" ""
			(at 128.27 152.4 0)
			(effects
				(font
					(size 1.27 1.27)
				)
			)
		)
		(property "Manufacturer" "YAGEO"
			(at 118.11 147.32 0)
			(effects
				(font
					(size 1.27 1.27)
					(thickness 0.15)
				)
				(justify left bottom)
				(hide yes)
			)
		)
		(property "MPN" "CC0201KRX6S5BB104"
			(at 120.65 147.32 0)
			(effects
				(font
					(size 1.27 1.27)
					(thickness 0.15)
				)
				(justify left bottom)
				(hide yes)
			)
		)
		(property "Val" "100n"
			(at 128.905 151.765 90)
			(effects
				(font
					(size 1.27 1.27)
					(thickness 0.15)
				)
				(justify right)
			)
		)
		(property "License" "Apache-2.0"
			(at 151.13 132.08 0)
			(effects
				(font
					(size 1.27 1.27)
					(thickness 0.15)
				)
				(justify left bottom)
				(hide yes)
			)
		)
		(property "Author" "Antmicro"
			(at 153.67 132.08 0)
			(effects
				(font
					(size 1.27 1.27)
					(thickness 0.15)
				)
				(justify left bottom)
				(hide yes)
			)
		)
		(property "Voltage" ""
			(at 156.21 132.08 0)
			(effects
				(font
					(size 1.27 1.27)
				)
				(justify left bottom)
				(hide yes)
			)
		)
		(property "Dielectric" ""
			(at 158.75 132.08 0)
			(effects
				(font
					(size 1.27 1.27)
				)
				(justify left bottom)
				(hide yes)
			)
		)
		(pin "1"
		)
		(pin "2"
		)
		(instances
			(project "lpddr4-testbed"
				(path ""
					(reference "C14")
					(unit 1)
				)
			)
		)
	)
	(symbol
		(lib_id "antmicroCapacitorsmisc:C_100n_0201")
		(at 142.24 152.4 90)
		(unit 1)
		(exclude_from_sim no)
		(in_bom yes)
		(on_board yes)
		(dnp no)
		(property "Reference" "C17"
			(at 142.875 147.955 90)
			(effects
				(font
					(size 1.27 1.27)
					(thickness 0.15)
				)
				(justify right)
			)
		)
		(property "Value" "C_100n_0201"
			(at 146.05 152.4 0)
			(effects
				(font
					(size 1.27 1.27)
					(thickness 0.15)
				)
				(justify left bottom)
				(hide yes)
			)
		)
		(property "Footprint" "antmicro-footprints:C_0201"
			(at 137.16 147.32 0)
			(effects
				(font
					(size 1.27 1.27)
					(thickness 0.15)
				)
				(justify left bottom)
				(hide yes)
			)
		)
		(property "Datasheet" ""
			(at 142.24 152.4 0)
			(effects
				(font
					(size 1.27 1.27)
					(thickness 0.15)
				)
				(justify left bottom)
				(hide yes)
			)
		)
		(property "Description" ""
			(at 142.24 152.4 0)
			(effects
				(font
					(size 1.27 1.27)
				)
			)
		)
		(property "Manufacturer" "YAGEO"
			(at 132.08 147.32 0)
			(effects
				(font
					(size 1.27 1.27)
					(thickness 0.15)
				)
				(justify left bottom)
				(hide yes)
			)
		)
		(property "MPN" "CC0201KRX6S5BB104"
			(at 134.62 147.32 0)
			(effects
				(font
					(size 1.27 1.27)
					(thickness 0.15)
				)
				(justify left bottom)
				(hide yes)
			)
		)
		(property "Val" "100n"
			(at 142.875 151.765 90)
			(effects
				(font
					(size 1.27 1.27)
					(thickness 0.15)
				)
				(justify right)
			)
		)
		(property "License" "Apache-2.0"
			(at 165.1 132.08 0)
			(effects
				(font
					(size 1.27 1.27)
					(thickness 0.15)
				)
				(justify left bottom)
				(hide yes)
			)
		)
		(property "Author" "Antmicro"
			(at 167.64 132.08 0)
			(effects
				(font
					(size 1.27 1.27)
					(thickness 0.15)
				)
				(justify left bottom)
				(hide yes)
			)
		)
		(property "Voltage" ""
			(at 170.18 132.08 0)
			(effects
				(font
					(size 1.27 1.27)
				)
				(justify left bottom)
				(hide yes)
			)
		)
		(property "Dielectric" ""
			(at 172.72 132.08 0)
			(effects
				(font
					(size 1.27 1.27)
				)
				(justify left bottom)
				(hide yes)
			)
		)
		(pin "1"
		)
		(pin "2"
		)
		(instances
			(project "lpddr4-testbed"
				(path ""
					(reference "C17")
					(unit 1)
				)
			)
		)
	)
	(symbol
		(lib_id "antmicroCapacitorsmisc:C_100n_0201")
		(at 114.3 67.31 90)
		(unit 1)
		(exclude_from_sim no)
		(in_bom yes)
		(on_board yes)
		(dnp no)
		(property "Reference" "C24"
			(at 114.935 62.865 90)
			(effects
				(font
					(size 1.27 1.27)
					(thickness 0.15)
				)
				(justify right)
			)
		)
		(property "Value" "C_100n_0201"
			(at 118.11 67.31 0)
			(effects
				(font
					(size 1.27 1.27)
					(thickness 0.15)
				)
				(justify left bottom)
				(hide yes)
			)
		)
		(property "Footprint" "antmicro-footprints:C_0201"
			(at 109.22 62.23 0)
			(effects
				(font
					(size 1.27 1.27)
					(thickness 0.15)
				)
				(justify left bottom)
				(hide yes)
			)
		)
		(property "Datasheet" ""
			(at 114.3 67.31 0)
			(effects
				(font
					(size 1.27 1.27)
					(thickness 0.15)
				)
				(justify left bottom)
				(hide yes)
			)
		)
		(property "Description" ""
			(at 114.3 67.31 0)
			(effects
				(font
					(size 1.27 1.27)
				)
			)
		)
		(property "Manufacturer" "YAGEO"
			(at 104.14 62.23 0)
			(effects
				(font
					(size 1.27 1.27)
					(thickness 0.15)
				)
				(justify left bottom)
				(hide yes)
			)
		)
		(property "MPN" "CC0201KRX6S5BB104"
			(at 106.68 62.23 0)
			(effects
				(font
					(size 1.27 1.27)
					(thickness 0.15)
				)
				(justify left bottom)
				(hide yes)
			)
		)
		(property "Val" "100n"
			(at 114.935 66.675 90)
			(effects
				(font
					(size 1.27 1.27)
					(thickness 0.15)
				)
				(justify right)
			)
		)
		(property "License" "Apache-2.0"
			(at 137.16 46.99 0)
			(effects
				(font
					(size 1.27 1.27)
					(thickness 0.15)
				)
				(justify left bottom)
				(hide yes)
			)
		)
		(property "Author" "Antmicro"
			(at 139.7 46.99 0)
			(effects
				(font
					(size 1.27 1.27)
					(thickness 0.15)
				)
				(justify left bottom)
				(hide yes)
			)
		)
		(property "Voltage" ""
			(at 142.24 46.99 0)
			(effects
				(font
					(size 1.27 1.27)
				)
				(justify left bottom)
				(hide yes)
			)
		)
		(property "Dielectric" ""
			(at 144.78 46.99 0)
			(effects
				(font
					(size 1.27 1.27)
				)
				(justify left bottom)
				(hide yes)
			)
		)
		(pin "1"
		)
		(pin "2"
		)
		(instances
			(project "lpddr4-testbed"
				(path ""
					(reference "C24")
					(unit 1)
				)
			)
		)
	)
	(symbol
		(lib_id "antmicroCapacitorsmisc:C_100n_0201")
		(at 121.285 67.31 90)
		(unit 1)
		(exclude_from_sim no)
		(in_bom yes)
		(on_board yes)
		(dnp no)
		(property "Reference" "C25"
			(at 121.92 62.865 90)
			(effects
				(font
					(size 1.27 1.27)
					(thickness 0.15)
				)
				(justify right)
			)
		)
		(property "Value" "C_100n_0201"
			(at 125.095 67.31 0)
			(effects
				(font
					(size 1.27 1.27)
					(thickness 0.15)
				)
				(justify left bottom)
				(hide yes)
			)
		)
		(property "Footprint" "antmicro-footprints:C_0201"
			(at 116.205 62.23 0)
			(effects
				(font
					(size 1.27 1.27)
					(thickness 0.15)
				)
				(justify left bottom)
				(hide yes)
			)
		)
		(property "Datasheet" ""
			(at 121.285 67.31 0)
			(effects
				(font
					(size 1.27 1.27)
					(thickness 0.15)
				)
				(justify left bottom)
				(hide yes)
			)
		)
		(property "Description" ""
			(at 121.285 67.31 0)
			(effects
				(font
					(size 1.27 1.27)
				)
			)
		)
		(property "Manufacturer" "YAGEO"
			(at 111.125 62.23 0)
			(effects
				(font
					(size 1.27 1.27)
					(thickness 0.15)
				)
				(justify left bottom)
				(hide yes)
			)
		)
		(property "MPN" "CC0201KRX6S5BB104"
			(at 113.665 62.23 0)
			(effects
				(font
					(size 1.27 1.27)
					(thickness 0.15)
				)
				(justify left bottom)
				(hide yes)
			)
		)
		(property "Val" "100n"
			(at 121.92 66.675 90)
			(effects
				(font
					(size 1.27 1.27)
					(thickness 0.15)
				)
				(justify right)
			)
		)
		(property "License" "Apache-2.0"
			(at 144.145 46.99 0)
			(effects
				(font
					(size 1.27 1.27)
					(thickness 0.15)
				)
				(justify left bottom)
				(hide yes)
			)
		)
		(property "Author" "Antmicro"
			(at 146.685 46.99 0)
			(effects
				(font
					(size 1.27 1.27)
					(thickness 0.15)
				)
				(justify left bottom)
				(hide yes)
			)
		)
		(property "Voltage" ""
			(at 149.225 46.99 0)
			(effects
				(font
					(size 1.27 1.27)
				)
				(justify left bottom)
				(hide yes)
			)
		)
		(property "Dielectric" ""
			(at 151.765 46.99 0)
			(effects
				(font
					(size 1.27 1.27)
				)
				(justify left bottom)
				(hide yes)
			)
		)
		(pin "1"
		)
		(pin "2"
		)
		(instances
			(project "lpddr4-testbed"
				(path ""
					(reference "C25")
					(unit 1)
				)
			)
		)
	)
	(symbol
		(lib_id "antmicroCapacitorsmisc:C_100n_0201")
		(at 128.27 67.31 90)
		(unit 1)
		(exclude_from_sim no)
		(in_bom yes)
		(on_board yes)
		(dnp no)
		(property "Reference" "C27"
			(at 128.905 62.865 90)
			(effects
				(font
					(size 1.27 1.27)
					(thickness 0.15)
				)
				(justify right)
			)
		)
		(property "Value" "C_100n_0201"
			(at 132.08 67.31 0)
			(effects
				(font
					(size 1.27 1.27)
					(thickness 0.15)
				)
				(justify left bottom)
				(hide yes)
			)
		)
		(property "Footprint" "antmicro-footprints:C_0201"
			(at 123.19 62.23 0)
			(effects
				(font
					(size 1.27 1.27)
					(thickness 0.15)
				)
				(justify left bottom)
				(hide yes)
			)
		)
		(property "Datasheet" ""
			(at 128.27 67.31 0)
			(effects
				(font
					(size 1.27 1.27)
					(thickness 0.15)
				)
				(justify left bottom)
				(hide yes)
			)
		)
		(property "Description" ""
			(at 128.27 67.31 0)
			(effects
				(font
					(size 1.27 1.27)
				)
			)
		)
		(property "Manufacturer" "YAGEO"
			(at 118.11 62.23 0)
			(effects
				(font
					(size 1.27 1.27)
					(thickness 0.15)
				)
				(justify left bottom)
				(hide yes)
			)
		)
		(property "MPN" "CC0201KRX6S5BB104"
			(at 120.65 62.23 0)
			(effects
				(font
					(size 1.27 1.27)
					(thickness 0.15)
				)
				(justify left bottom)
				(hide yes)
			)
		)
		(property "Val" "100n"
			(at 128.905 66.675 90)
			(effects
				(font
					(size 1.27 1.27)
					(thickness 0.15)
				)
				(justify right)
			)
		)
		(property "License" "Apache-2.0"
			(at 151.13 46.99 0)
			(effects
				(font
					(size 1.27 1.27)
					(thickness 0.15)
				)
				(justify left bottom)
				(hide yes)
			)
		)
		(property "Author" "Antmicro"
			(at 153.67 46.99 0)
			(effects
				(font
					(size 1.27 1.27)
					(thickness 0.15)
				)
				(justify left bottom)
				(hide yes)
			)
		)
		(property "Voltage" ""
			(at 156.21 46.99 0)
			(effects
				(font
					(size 1.27 1.27)
				)
				(justify left bottom)
				(hide yes)
			)
		)
		(property "Dielectric" ""
			(at 158.75 46.99 0)
			(effects
				(font
					(size 1.27 1.27)
				)
				(justify left bottom)
				(hide yes)
			)
		)
		(pin "1"
		)
		(pin "2"
		)
		(instances
			(project "lpddr4-testbed"
				(path ""
					(reference "C27")
					(unit 1)
				)
			)
		)
	)
	(symbol
		(lib_id "antmicroCapacitorsmisc:C_100n_0201")
		(at 114.3 167.64 90)
		(unit 1)
		(exclude_from_sim no)
		(in_bom yes)
		(on_board yes)
		(dnp no)
		(property "Reference" "C29"
			(at 114.935 163.195 90)
			(effects
				(font
					(size 1.27 1.27)
					(thickness 0.15)
				)
				(justify right)
			)
		)
		(property "Value" "C_100n_0201"
			(at 118.11 167.64 0)
			(effects
				(font
					(size 1.27 1.27)
					(thickness 0.15)
				)
				(justify left bottom)
				(hide yes)
			)
		)
		(property "Footprint" "antmicro-footprints:C_0201"
			(at 109.22 162.56 0)
			(effects
				(font
					(size 1.27 1.27)
					(thickness 0.15)
				)
				(justify left bottom)
				(hide yes)
			)
		)
		(property "Datasheet" ""
			(at 114.3 167.64 0)
			(effects
				(font
					(size 1.27 1.27)
					(thickness 0.15)
				)
				(justify left bottom)
				(hide yes)
			)
		)
		(property "Description" ""
			(at 114.3 167.64 0)
			(effects
				(font
					(size 1.27 1.27)
				)
			)
		)
		(property "Manufacturer" "YAGEO"
			(at 104.14 162.56 0)
			(effects
				(font
					(size 1.27 1.27)
					(thickness 0.15)
				)
				(justify left bottom)
				(hide yes)
			)
		)
		(property "MPN" "CC0201KRX6S5BB104"
			(at 106.68 162.56 0)
			(effects
				(font
					(size 1.27 1.27)
					(thickness 0.15)
				)
				(justify left bottom)
				(hide yes)
			)
		)
		(property "Val" "100n"
			(at 114.935 167.005 90)
			(effects
				(font
					(size 1.27 1.27)
					(thickness 0.15)
				)
				(justify right)
			)
		)
		(property "License" "Apache-2.0"
			(at 137.16 147.32 0)
			(effects
				(font
					(size 1.27 1.27)
					(thickness 0.15)
				)
				(justify left bottom)
				(hide yes)
			)
		)
		(property "Author" "Antmicro"
			(at 139.7 147.32 0)
			(effects
				(font
					(size 1.27 1.27)
					(thickness 0.15)
				)
				(justify left bottom)
				(hide yes)
			)
		)
		(property "Voltage" ""
			(at 142.24 147.32 0)
			(effects
				(font
					(size 1.27 1.27)
				)
				(justify left bottom)
				(hide yes)
			)
		)
		(property "Dielectric" ""
			(at 144.78 147.32 0)
			(effects
				(font
					(size 1.27 1.27)
				)
				(justify left bottom)
				(hide yes)
			)
		)
		(pin "1"
		)
		(pin "2"
		)
		(instances
			(project "lpddr4-testbed"
				(path ""
					(reference "C29")
					(unit 1)
				)
			)
		)
	)
	(symbol
		(lib_id "antmicroCapacitorsmisc:C_100n_0201")
		(at 114.3 182.88 90)
		(unit 1)
		(exclude_from_sim no)
		(in_bom yes)
		(on_board yes)
		(dnp no)
		(property "Reference" "C3"
			(at 114.935 178.435 90)
			(effects
				(font
					(size 1.27 1.27)
					(thickness 0.15)
				)
				(justify right)
			)
		)
		(property "Value" "C_100n_0201"
			(at 118.11 182.88 0)
			(effects
				(font
					(size 1.27 1.27)
					(thickness 0.15)
				)
				(justify left bottom)
				(hide yes)
			)
		)
		(property "Footprint" "antmicro-footprints:C_0201"
			(at 109.22 177.8 0)
			(effects
				(font
					(size 1.27 1.27)
					(thickness 0.15)
				)
				(justify left bottom)
				(hide yes)
			)
		)
		(property "Datasheet" ""
			(at 114.3 182.88 0)
			(effects
				(font
					(size 1.27 1.27)
					(thickness 0.15)
				)
				(justify left bottom)
				(hide yes)
			)
		)
		(property "Description" ""
			(at 114.3 182.88 0)
			(effects
				(font
					(size 1.27 1.27)
				)
			)
		)
		(property "Manufacturer" "YAGEO"
			(at 104.14 177.8 0)
			(effects
				(font
					(size 1.27 1.27)
					(thickness 0.15)
				)
				(justify left bottom)
				(hide yes)
			)
		)
		(property "MPN" "CC0201KRX6S5BB104"
			(at 106.68 177.8 0)
			(effects
				(font
					(size 1.27 1.27)
					(thickness 0.15)
				)
				(justify left bottom)
				(hide yes)
			)
		)
		(property "Val" "100n"
			(at 114.935 182.245 90)
			(effects
				(font
					(size 1.27 1.27)
					(thickness 0.15)
				)
				(justify right)
			)
		)
		(property "License" "Apache-2.0"
			(at 137.16 162.56 0)
			(effects
				(font
					(size 1.27 1.27)
					(thickness 0.15)
				)
				(justify left bottom)
				(hide yes)
			)
		)
		(property "Author" "Antmicro"
			(at 139.7 162.56 0)
			(effects
				(font
					(size 1.27 1.27)
					(thickness 0.15)
				)
				(justify left bottom)
				(hide yes)
			)
		)
		(property "Voltage" ""
			(at 142.24 162.56 0)
			(effects
				(font
					(size 1.27 1.27)
				)
				(justify left bottom)
				(hide yes)
			)
		)
		(property "Dielectric" ""
			(at 144.78 162.56 0)
			(effects
				(font
					(size 1.27 1.27)
				)
				(justify left bottom)
				(hide yes)
			)
		)
		(pin "1"
		)
		(pin "2"
		)
		(instances
			(project "lpddr4-testbed"
				(path ""
					(reference "C3")
					(unit 1)
				)
			)
		)
	)
	(symbol
		(lib_id "antmicroCapacitorsmisc:C_100n_0201")
		(at 121.285 182.88 90)
		(unit 1)
		(exclude_from_sim no)
		(in_bom yes)
		(on_board yes)
		(dnp no)
		(property "Reference" "C6"
			(at 121.92 178.435 90)
			(effects
				(font
					(size 1.27 1.27)
					(thickness 0.15)
				)
				(justify right)
			)
		)
		(property "Value" "C_100n_0201"
			(at 125.095 182.88 0)
			(effects
				(font
					(size 1.27 1.27)
					(thickness 0.15)
				)
				(justify left bottom)
				(hide yes)
			)
		)
		(property "Footprint" "antmicro-footprints:C_0201"
			(at 116.205 177.8 0)
			(effects
				(font
					(size 1.27 1.27)
					(thickness 0.15)
				)
				(justify left bottom)
				(hide yes)
			)
		)
		(property "Datasheet" ""
			(at 121.285 182.88 0)
			(effects
				(font
					(size 1.27 1.27)
					(thickness 0.15)
				)
				(justify left bottom)
				(hide yes)
			)
		)
		(property "Description" ""
			(at 121.285 182.88 0)
			(effects
				(font
					(size 1.27 1.27)
				)
			)
		)
		(property "Manufacturer" "YAGEO"
			(at 111.125 177.8 0)
			(effects
				(font
					(size 1.27 1.27)
					(thickness 0.15)
				)
				(justify left bottom)
				(hide yes)
			)
		)
		(property "MPN" "CC0201KRX6S5BB104"
			(at 113.665 177.8 0)
			(effects
				(font
					(size 1.27 1.27)
					(thickness 0.15)
				)
				(justify left bottom)
				(hide yes)
			)
		)
		(property "Val" "100n"
			(at 121.92 182.245 90)
			(effects
				(font
					(size 1.27 1.27)
					(thickness 0.15)
				)
				(justify right)
			)
		)
		(property "License" "Apache-2.0"
			(at 144.145 162.56 0)
			(effects
				(font
					(size 1.27 1.27)
					(thickness 0.15)
				)
				(justify left bottom)
				(hide yes)
			)
		)
		(property "Author" "Antmicro"
			(at 146.685 162.56 0)
			(effects
				(font
					(size 1.27 1.27)
					(thickness 0.15)
				)
				(justify left bottom)
				(hide yes)
			)
		)
		(property "Voltage" ""
			(at 149.225 162.56 0)
			(effects
				(font
					(size 1.27 1.27)
				)
				(justify left bottom)
				(hide yes)
			)
		)
		(property "Dielectric" ""
			(at 151.765 162.56 0)
			(effects
				(font
					(size 1.27 1.27)
				)
				(justify left bottom)
				(hide yes)
			)
		)
		(pin "1"
		)
		(pin "2"
		)
		(instances
			(project "lpddr4-testbed"
				(path ""
					(reference "C6")
					(unit 1)
				)
			)
		)
	)
	(symbol
		(lib_id "antmicroCapacitorsmisc:C_100n_0201")
		(at 128.27 182.88 90)
		(unit 1)
		(exclude_from_sim no)
		(in_bom yes)
		(on_board yes)
		(dnp no)
		(property "Reference" "C9"
			(at 128.905 178.435 90)
			(effects
				(font
					(size 1.27 1.27)
					(thickness 0.15)
				)
				(justify right)
			)
		)
		(property "Value" "C_100n_0201"
			(at 132.08 182.88 0)
			(effects
				(font
					(size 1.27 1.27)
					(thickness 0.15)
				)
				(justify left bottom)
				(hide yes)
			)
		)
		(property "Footprint" "antmicro-footprints:C_0201"
			(at 123.19 177.8 0)
			(effects
				(font
					(size 1.27 1.27)
					(thickness 0.15)
				)
				(justify left bottom)
				(hide yes)
			)
		)
		(property "Datasheet" ""
			(at 128.27 182.88 0)
			(effects
				(font
					(size 1.27 1.27)
					(thickness 0.15)
				)
				(justify left bottom)
				(hide yes)
			)
		)
		(property "Description" ""
			(at 128.27 182.88 0)
			(effects
				(font
					(size 1.27 1.27)
				)
			)
		)
		(property "Manufacturer" "YAGEO"
			(at 118.11 177.8 0)
			(effects
				(font
					(size 1.27 1.27)
					(thickness 0.15)
				)
				(justify left bottom)
				(hide yes)
			)
		)
		(property "MPN" "CC0201KRX6S5BB104"
			(at 120.65 177.8 0)
			(effects
				(font
					(size 1.27 1.27)
					(thickness 0.15)
				)
				(justify left bottom)
				(hide yes)
			)
		)
		(property "Val" "100n"
			(at 128.905 182.245 90)
			(effects
				(font
					(size 1.27 1.27)
					(thickness 0.15)
				)
				(justify right)
			)
		)
		(property "License" "Apache-2.0"
			(at 151.13 162.56 0)
			(effects
				(font
					(size 1.27 1.27)
					(thickness 0.15)
				)
				(justify left bottom)
				(hide yes)
			)
		)
		(property "Author" "Antmicro"
			(at 153.67 162.56 0)
			(effects
				(font
					(size 1.27 1.27)
					(thickness 0.15)
				)
				(justify left bottom)
				(hide yes)
			)
		)
		(property "Voltage" ""
			(at 156.21 162.56 0)
			(effects
				(font
					(size 1.27 1.27)
				)
				(justify left bottom)
				(hide yes)
			)
		)
		(property "Dielectric" ""
			(at 158.75 162.56 0)
			(effects
				(font
					(size 1.27 1.27)
				)
				(justify left bottom)
				(hide yes)
			)
		)
		(pin "1"
		)
		(pin "2"
		)
		(instances
			(project "lpddr4-testbed"
				(path ""
					(reference "C9")
					(unit 1)
				)
			)
		)
	)
	(symbol
		(lib_id "antmicroCapacitorsmisc:C_100n_0201")
		(at 135.255 182.88 90)
		(unit 1)
		(exclude_from_sim no)
		(in_bom yes)
		(on_board yes)
		(dnp no)
		(property "Reference" "C12"
			(at 135.89 178.435 90)
			(effects
				(font
					(size 1.27 1.27)
					(thickness 0.15)
				)
				(justify right)
			)
		)
		(property "Value" "C_100n_0201"
			(at 139.065 182.88 0)
			(effects
				(font
					(size 1.27 1.27)
					(thickness 0.15)
				)
				(justify left bottom)
				(hide yes)
			)
		)
		(property "Footprint" "antmicro-footprints:C_0201"
			(at 130.175 177.8 0)
			(effects
				(font
					(size 1.27 1.27)
					(thickness 0.15)
				)
				(justify left bottom)
				(hide yes)
			)
		)
		(property "Datasheet" ""
			(at 135.255 182.88 0)
			(effects
				(font
					(size 1.27 1.27)
					(thickness 0.15)
				)
				(justify left bottom)
				(hide yes)
			)
		)
		(property "Description" ""
			(at 135.255 182.88 0)
			(effects
				(font
					(size 1.27 1.27)
				)
			)
		)
		(property "Manufacturer" "YAGEO"
			(at 125.095 177.8 0)
			(effects
				(font
					(size 1.27 1.27)
					(thickness 0.15)
				)
				(justify left bottom)
				(hide yes)
			)
		)
		(property "MPN" "CC0201KRX6S5BB104"
			(at 127.635 177.8 0)
			(effects
				(font
					(size 1.27 1.27)
					(thickness 0.15)
				)
				(justify left bottom)
				(hide yes)
			)
		)
		(property "Val" "100n"
			(at 135.89 182.245 90)
			(effects
				(font
					(size 1.27 1.27)
					(thickness 0.15)
				)
				(justify right)
			)
		)
		(property "License" "Apache-2.0"
			(at 158.115 162.56 0)
			(effects
				(font
					(size 1.27 1.27)
					(thickness 0.15)
				)
				(justify left bottom)
				(hide yes)
			)
		)
		(property "Author" "Antmicro"
			(at 160.655 162.56 0)
			(effects
				(font
					(size 1.27 1.27)
					(thickness 0.15)
				)
				(justify left bottom)
				(hide yes)
			)
		)
		(property "Voltage" ""
			(at 163.195 162.56 0)
			(effects
				(font
					(size 1.27 1.27)
				)
				(justify left bottom)
				(hide yes)
			)
		)
		(property "Dielectric" ""
			(at 165.735 162.56 0)
			(effects
				(font
					(size 1.27 1.27)
				)
				(justify left bottom)
				(hide yes)
			)
		)
		(pin "1"
		)
		(pin "2"
		)
		(instances
			(project "lpddr4-testbed"
				(path ""
					(reference "C12")
					(unit 1)
				)
			)
		)
	)
	(symbol
		(lib_id "antmicroCapacitorsmisc:C_100n_0201")
		(at 121.285 167.64 90)
		(unit 1)
		(exclude_from_sim no)
		(in_bom yes)
		(on_board yes)
		(dnp no)
		(property "Reference" "C31"
			(at 121.92 163.195 90)
			(effects
				(font
					(size 1.27 1.27)
					(thickness 0.15)
				)
				(justify right)
			)
		)
		(property "Value" "C_100n_0201"
			(at 125.095 167.64 0)
			(effects
				(font
					(size 1.27 1.27)
					(thickness 0.15)
				)
				(justify left bottom)
				(hide yes)
			)
		)
		(property "Footprint" "antmicro-footprints:C_0201"
			(at 116.205 162.56 0)
			(effects
				(font
					(size 1.27 1.27)
					(thickness 0.15)
				)
				(justify left bottom)
				(hide yes)
			)
		)
		(property "Datasheet" ""
			(at 121.285 167.64 0)
			(effects
				(font
					(size 1.27 1.27)
					(thickness 0.15)
				)
				(justify left bottom)
				(hide yes)
			)
		)
		(property "Description" ""
			(at 121.285 167.64 0)
			(effects
				(font
					(size 1.27 1.27)
				)
			)
		)
		(property "Manufacturer" "YAGEO"
			(at 111.125 162.56 0)
			(effects
				(font
					(size 1.27 1.27)
					(thickness 0.15)
				)
				(justify left bottom)
				(hide yes)
			)
		)
		(property "MPN" "CC0201KRX6S5BB104"
			(at 113.665 162.56 0)
			(effects
				(font
					(size 1.27 1.27)
					(thickness 0.15)
				)
				(justify left bottom)
				(hide yes)
			)
		)
		(property "Val" "100n"
			(at 121.92 167.005 90)
			(effects
				(font
					(size 1.27 1.27)
					(thickness 0.15)
				)
				(justify right)
			)
		)
		(property "License" "Apache-2.0"
			(at 144.145 147.32 0)
			(effects
				(font
					(size 1.27 1.27)
					(thickness 0.15)
				)
				(justify left bottom)
				(hide yes)
			)
		)
		(property "Author" "Antmicro"
			(at 146.685 147.32 0)
			(effects
				(font
					(size 1.27 1.27)
					(thickness 0.15)
				)
				(justify left bottom)
				(hide yes)
			)
		)
		(property "Voltage" ""
			(at 149.225 147.32 0)
			(effects
				(font
					(size 1.27 1.27)
				)
				(justify left bottom)
				(hide yes)
			)
		)
		(property "Dielectric" ""
			(at 151.765 147.32 0)
			(effects
				(font
					(size 1.27 1.27)
				)
				(justify left bottom)
				(hide yes)
			)
		)
		(pin "1"
		)
		(pin "2"
		)
		(instances
			(project "lpddr4-testbed"
				(path ""
					(reference "C31")
					(unit 1)
				)
			)
		)
	)
	(symbol
		(lib_id "antmicroCapacitorsmisc:C_100n_0201")
		(at 142.24 182.88 90)
		(unit 1)
		(exclude_from_sim no)
		(in_bom yes)
		(on_board yes)
		(dnp no)
		(property "Reference" "C15"
			(at 142.875 178.435 90)
			(effects
				(font
					(size 1.27 1.27)
					(thickness 0.15)
				)
				(justify right)
			)
		)
		(property "Value" "C_100n_0201"
			(at 146.05 182.88 0)
			(effects
				(font
					(size 1.27 1.27)
					(thickness 0.15)
				)
				(justify left bottom)
				(hide yes)
			)
		)
		(property "Footprint" "antmicro-footprints:C_0201"
			(at 137.16 177.8 0)
			(effects
				(font
					(size 1.27 1.27)
					(thickness 0.15)
				)
				(justify left bottom)
				(hide yes)
			)
		)
		(property "Datasheet" ""
			(at 142.24 182.88 0)
			(effects
				(font
					(size 1.27 1.27)
					(thickness 0.15)
				)
				(justify left bottom)
				(hide yes)
			)
		)
		(property "Description" ""
			(at 142.24 182.88 0)
			(effects
				(font
					(size 1.27 1.27)
				)
			)
		)
		(property "Manufacturer" "YAGEO"
			(at 132.08 177.8 0)
			(effects
				(font
					(size 1.27 1.27)
					(thickness 0.15)
				)
				(justify left bottom)
				(hide yes)
			)
		)
		(property "MPN" "CC0201KRX6S5BB104"
			(at 134.62 177.8 0)
			(effects
				(font
					(size 1.27 1.27)
					(thickness 0.15)
				)
				(justify left bottom)
				(hide yes)
			)
		)
		(property "Val" "100n"
			(at 142.875 182.245 90)
			(effects
				(font
					(size 1.27 1.27)
					(thickness 0.15)
				)
				(justify right)
			)
		)
		(property "License" "Apache-2.0"
			(at 165.1 162.56 0)
			(effects
				(font
					(size 1.27 1.27)
					(thickness 0.15)
				)
				(justify left bottom)
				(hide yes)
			)
		)
		(property "Author" "Antmicro"
			(at 167.64 162.56 0)
			(effects
				(font
					(size 1.27 1.27)
					(thickness 0.15)
				)
				(justify left bottom)
				(hide yes)
			)
		)
		(property "Voltage" ""
			(at 170.18 162.56 0)
			(effects
				(font
					(size 1.27 1.27)
				)
				(justify left bottom)
				(hide yes)
			)
		)
		(property "Dielectric" ""
			(at 172.72 162.56 0)
			(effects
				(font
					(size 1.27 1.27)
				)
				(justify left bottom)
				(hide yes)
			)
		)
		(pin "1"
		)
		(pin "2"
		)
		(instances
			(project "lpddr4-testbed"
				(path ""
					(reference "C15")
					(unit 1)
				)
			)
		)
	)
	(symbol
		(lib_id "antmicroCapacitorsmisc:C_100n_0201")
		(at 149.225 182.88 90)
		(unit 1)
		(exclude_from_sim no)
		(in_bom yes)
		(on_board yes)
		(dnp no)
		(property "Reference" "C18"
			(at 149.86 178.435 90)
			(effects
				(font
					(size 1.27 1.27)
					(thickness 0.15)
				)
				(justify right)
			)
		)
		(property "Value" "C_100n_0201"
			(at 153.035 182.88 0)
			(effects
				(font
					(size 1.27 1.27)
					(thickness 0.15)
				)
				(justify left bottom)
				(hide yes)
			)
		)
		(property "Footprint" "antmicro-footprints:C_0201"
			(at 144.145 177.8 0)
			(effects
				(font
					(size 1.27 1.27)
					(thickness 0.15)
				)
				(justify left bottom)
				(hide yes)
			)
		)
		(property "Datasheet" ""
			(at 149.225 182.88 0)
			(effects
				(font
					(size 1.27 1.27)
					(thickness 0.15)
				)
				(justify left bottom)
				(hide yes)
			)
		)
		(property "Description" ""
			(at 149.225 182.88 0)
			(effects
				(font
					(size 1.27 1.27)
				)
			)
		)
		(property "Manufacturer" "YAGEO"
			(at 139.065 177.8 0)
			(effects
				(font
					(size 1.27 1.27)
					(thickness 0.15)
				)
				(justify left bottom)
				(hide yes)
			)
		)
		(property "MPN" "CC0201KRX6S5BB104"
			(at 141.605 177.8 0)
			(effects
				(font
					(size 1.27 1.27)
					(thickness 0.15)
				)
				(justify left bottom)
				(hide yes)
			)
		)
		(property "Val" "100n"
			(at 149.86 182.245 90)
			(effects
				(font
					(size 1.27 1.27)
					(thickness 0.15)
				)
				(justify right)
			)
		)
		(property "License" "Apache-2.0"
			(at 172.085 162.56 0)
			(effects
				(font
					(size 1.27 1.27)
					(thickness 0.15)
				)
				(justify left bottom)
				(hide yes)
			)
		)
		(property "Author" "Antmicro"
			(at 174.625 162.56 0)
			(effects
				(font
					(size 1.27 1.27)
					(thickness 0.15)
				)
				(justify left bottom)
				(hide yes)
			)
		)
		(property "Voltage" ""
			(at 177.165 162.56 0)
			(effects
				(font
					(size 1.27 1.27)
				)
				(justify left bottom)
				(hide yes)
			)
		)
		(property "Dielectric" ""
			(at 179.705 162.56 0)
			(effects
				(font
					(size 1.27 1.27)
				)
				(justify left bottom)
				(hide yes)
			)
		)
		(pin "1"
		)
		(pin "2"
		)
		(instances
			(project "lpddr4-testbed"
				(path ""
					(reference "C18")
					(unit 1)
				)
			)
		)
	)
	(symbol
		(lib_id "antmicroCapacitorsmisc:C_100n_0201")
		(at 156.21 182.88 90)
		(unit 1)
		(exclude_from_sim no)
		(in_bom yes)
		(on_board yes)
		(dnp no)
		(property "Reference" "C20"
			(at 156.845 178.435 90)
			(effects
				(font
					(size 1.27 1.27)
					(thickness 0.15)
				)
				(justify right)
			)
		)
		(property "Value" "C_100n_0201"
			(at 160.02 182.88 0)
			(effects
				(font
					(size 1.27 1.27)
					(thickness 0.15)
				)
				(justify left bottom)
				(hide yes)
			)
		)
		(property "Footprint" "antmicro-footprints:C_0201"
			(at 151.13 177.8 0)
			(effects
				(font
					(size 1.27 1.27)
					(thickness 0.15)
				)
				(justify left bottom)
				(hide yes)
			)
		)
		(property "Datasheet" ""
			(at 156.21 182.88 0)
			(effects
				(font
					(size 1.27 1.27)
					(thickness 0.15)
				)
				(justify left bottom)
				(hide yes)
			)
		)
		(property "Description" ""
			(at 156.21 182.88 0)
			(effects
				(font
					(size 1.27 1.27)
				)
			)
		)
		(property "Manufacturer" "YAGEO"
			(at 146.05 177.8 0)
			(effects
				(font
					(size 1.27 1.27)
					(thickness 0.15)
				)
				(justify left bottom)
				(hide yes)
			)
		)
		(property "MPN" "CC0201KRX6S5BB104"
			(at 148.59 177.8 0)
			(effects
				(font
					(size 1.27 1.27)
					(thickness 0.15)
				)
				(justify left bottom)
				(hide yes)
			)
		)
		(property "Val" "100n"
			(at 156.845 182.245 90)
			(effects
				(font
					(size 1.27 1.27)
					(thickness 0.15)
				)
				(justify right)
			)
		)
		(property "License" "Apache-2.0"
			(at 179.07 162.56 0)
			(effects
				(font
					(size 1.27 1.27)
					(thickness 0.15)
				)
				(justify left bottom)
				(hide yes)
			)
		)
		(property "Author" "Antmicro"
			(at 181.61 162.56 0)
			(effects
				(font
					(size 1.27 1.27)
					(thickness 0.15)
				)
				(justify left bottom)
				(hide yes)
			)
		)
		(property "Voltage" ""
			(at 184.15 162.56 0)
			(effects
				(font
					(size 1.27 1.27)
				)
				(justify left bottom)
				(hide yes)
			)
		)
		(property "Dielectric" ""
			(at 186.69 162.56 0)
			(effects
				(font
					(size 1.27 1.27)
				)
				(justify left bottom)
				(hide yes)
			)
		)
		(pin "1"
		)
		(pin "2"
		)
		(instances
			(project "lpddr4-testbed"
				(path ""
					(reference "C20")
					(unit 1)
				)
			)
		)
	)
	(symbol
		(lib_id "antmicroCapacitorsmisc:C_100n_0201")
		(at 163.195 182.88 90)
		(unit 1)
		(exclude_from_sim no)
		(in_bom yes)
		(on_board yes)
		(dnp no)
		(property "Reference" "C22"
			(at 163.83 178.435 90)
			(effects
				(font
					(size 1.27 1.27)
					(thickness 0.15)
				)
				(justify right)
			)
		)
		(property "Value" "C_100n_0201"
			(at 167.005 182.88 0)
			(effects
				(font
					(size 1.27 1.27)
					(thickness 0.15)
				)
				(justify left bottom)
				(hide yes)
			)
		)
		(property "Footprint" "antmicro-footprints:C_0201"
			(at 158.115 177.8 0)
			(effects
				(font
					(size 1.27 1.27)
					(thickness 0.15)
				)
				(justify left bottom)
				(hide yes)
			)
		)
		(property "Datasheet" ""
			(at 163.195 182.88 0)
			(effects
				(font
					(size 1.27 1.27)
					(thickness 0.15)
				)
				(justify left bottom)
				(hide yes)
			)
		)
		(property "Description" ""
			(at 163.195 182.88 0)
			(effects
				(font
					(size 1.27 1.27)
				)
			)
		)
		(property "Manufacturer" "YAGEO"
			(at 153.035 177.8 0)
			(effects
				(font
					(size 1.27 1.27)
					(thickness 0.15)
				)
				(justify left bottom)
				(hide yes)
			)
		)
		(property "MPN" "CC0201KRX6S5BB104"
			(at 155.575 177.8 0)
			(effects
				(font
					(size 1.27 1.27)
					(thickness 0.15)
				)
				(justify left bottom)
				(hide yes)
			)
		)
		(property "Val" "100n"
			(at 163.83 182.245 90)
			(effects
				(font
					(size 1.27 1.27)
					(thickness 0.15)
				)
				(justify right)
			)
		)
		(property "License" "Apache-2.0"
			(at 186.055 162.56 0)
			(effects
				(font
					(size 1.27 1.27)
					(thickness 0.15)
				)
				(justify left bottom)
				(hide yes)
			)
		)
		(property "Author" "Antmicro"
			(at 188.595 162.56 0)
			(effects
				(font
					(size 1.27 1.27)
					(thickness 0.15)
				)
				(justify left bottom)
				(hide yes)
			)
		)
		(property "Voltage" ""
			(at 191.135 162.56 0)
			(effects
				(font
					(size 1.27 1.27)
				)
				(justify left bottom)
				(hide yes)
			)
		)
		(property "Dielectric" ""
			(at 193.675 162.56 0)
			(effects
				(font
					(size 1.27 1.27)
				)
				(justify left bottom)
				(hide yes)
			)
		)
		(pin "1"
		)
		(pin "2"
		)
		(instances
			(project "lpddr4-testbed"
				(path ""
					(reference "C22")
					(unit 1)
				)
			)
		)
	)
	(symbol
		(lib_id "antmicroCapacitorsmisc:C_100n_0201")
		(at 114.3 82.55 90)
		(unit 1)
		(exclude_from_sim no)
		(in_bom yes)
		(on_board yes)
		(dnp no)
		(property "Reference" "C23"
			(at 114.935 78.105 90)
			(effects
				(font
					(size 1.27 1.27)
					(thickness 0.15)
				)
				(justify right)
			)
		)
		(property "Value" "C_100n_0201"
			(at 118.11 82.55 0)
			(effects
				(font
					(size 1.27 1.27)
					(thickness 0.15)
				)
				(justify left bottom)
				(hide yes)
			)
		)
		(property "Footprint" "antmicro-footprints:C_0201"
			(at 109.22 77.47 0)
			(effects
				(font
					(size 1.27 1.27)
					(thickness 0.15)
				)
				(justify left bottom)
				(hide yes)
			)
		)
		(property "Datasheet" ""
			(at 114.3 82.55 0)
			(effects
				(font
					(size 1.27 1.27)
					(thickness 0.15)
				)
				(justify left bottom)
				(hide yes)
			)
		)
		(property "Description" ""
			(at 114.3 82.55 0)
			(effects
				(font
					(size 1.27 1.27)
				)
			)
		)
		(property "Manufacturer" "YAGEO"
			(at 104.14 77.47 0)
			(effects
				(font
					(size 1.27 1.27)
					(thickness 0.15)
				)
				(justify left bottom)
				(hide yes)
			)
		)
		(property "MPN" "CC0201KRX6S5BB104"
			(at 106.68 77.47 0)
			(effects
				(font
					(size 1.27 1.27)
					(thickness 0.15)
				)
				(justify left bottom)
				(hide yes)
			)
		)
		(property "Val" "100n"
			(at 114.935 81.915 90)
			(effects
				(font
					(size 1.27 1.27)
					(thickness 0.15)
				)
				(justify right)
			)
		)
		(property "License" "Apache-2.0"
			(at 137.16 62.23 0)
			(effects
				(font
					(size 1.27 1.27)
					(thickness 0.15)
				)
				(justify left bottom)
				(hide yes)
			)
		)
		(property "Author" "Antmicro"
			(at 139.7 62.23 0)
			(effects
				(font
					(size 1.27 1.27)
					(thickness 0.15)
				)
				(justify left bottom)
				(hide yes)
			)
		)
		(property "Voltage" ""
			(at 142.24 62.23 0)
			(effects
				(font
					(size 1.27 1.27)
				)
				(justify left bottom)
				(hide yes)
			)
		)
		(property "Dielectric" ""
			(at 144.78 62.23 0)
			(effects
				(font
					(size 1.27 1.27)
				)
				(justify left bottom)
				(hide yes)
			)
		)
		(pin "1"
		)
		(pin "2"
		)
		(instances
			(project "lpddr4-testbed"
				(path ""
					(reference "C23")
					(unit 1)
				)
			)
		)
	)
	(symbol
		(lib_id "antmicroCapacitorsmisc:C_100n_0201")
		(at 121.285 82.55 90)
		(unit 1)
		(exclude_from_sim no)
		(in_bom yes)
		(on_board yes)
		(dnp no)
		(property "Reference" "C26"
			(at 121.92 78.105 90)
			(effects
				(font
					(size 1.27 1.27)
					(thickness 0.15)
				)
				(justify right)
			)
		)
		(property "Value" "C_100n_0201"
			(at 125.095 82.55 0)
			(effects
				(font
					(size 1.27 1.27)
					(thickness 0.15)
				)
				(justify left bottom)
				(hide yes)
			)
		)
		(property "Footprint" "antmicro-footprints:C_0201"
			(at 116.205 77.47 0)
			(effects
				(font
					(size 1.27 1.27)
					(thickness 0.15)
				)
				(justify left bottom)
				(hide yes)
			)
		)
		(property "Datasheet" ""
			(at 121.285 82.55 0)
			(effects
				(font
					(size 1.27 1.27)
					(thickness 0.15)
				)
				(justify left bottom)
				(hide yes)
			)
		)
		(property "Description" ""
			(at 121.285 82.55 0)
			(effects
				(font
					(size 1.27 1.27)
				)
			)
		)
		(property "Manufacturer" "YAGEO"
			(at 111.125 77.47 0)
			(effects
				(font
					(size 1.27 1.27)
					(thickness 0.15)
				)
				(justify left bottom)
				(hide yes)
			)
		)
		(property "MPN" "CC0201KRX6S5BB104"
			(at 113.665 77.47 0)
			(effects
				(font
					(size 1.27 1.27)
					(thickness 0.15)
				)
				(justify left bottom)
				(hide yes)
			)
		)
		(property "Val" "100n"
			(at 121.92 81.915 90)
			(effects
				(font
					(size 1.27 1.27)
					(thickness 0.15)
				)
				(justify right)
			)
		)
		(property "License" "Apache-2.0"
			(at 144.145 62.23 0)
			(effects
				(font
					(size 1.27 1.27)
					(thickness 0.15)
				)
				(justify left bottom)
				(hide yes)
			)
		)
		(property "Author" "Antmicro"
			(at 146.685 62.23 0)
			(effects
				(font
					(size 1.27 1.27)
					(thickness 0.15)
				)
				(justify left bottom)
				(hide yes)
			)
		)
		(property "Voltage" ""
			(at 149.225 62.23 0)
			(effects
				(font
					(size 1.27 1.27)
				)
				(justify left bottom)
				(hide yes)
			)
		)
		(property "Dielectric" ""
			(at 151.765 62.23 0)
			(effects
				(font
					(size 1.27 1.27)
				)
				(justify left bottom)
				(hide yes)
			)
		)
		(pin "1"
		)
		(pin "2"
		)
		(instances
			(project "lpddr4-testbed"
				(path ""
					(reference "C26")
					(unit 1)
				)
			)
		)
	)
	(symbol
		(lib_id "antmicroCapacitorsmisc:C_100n_0201")
		(at 128.27 82.55 90)
		(unit 1)
		(exclude_from_sim no)
		(in_bom yes)
		(on_board yes)
		(dnp no)
		(property "Reference" "C28"
			(at 128.905 78.105 90)
			(effects
				(font
					(size 1.27 1.27)
					(thickness 0.15)
				)
				(justify right)
			)
		)
		(property "Value" "C_100n_0201"
			(at 132.08 82.55 0)
			(effects
				(font
					(size 1.27 1.27)
					(thickness 0.15)
				)
				(justify left bottom)
				(hide yes)
			)
		)
		(property "Footprint" "antmicro-footprints:C_0201"
			(at 123.19 77.47 0)
			(effects
				(font
					(size 1.27 1.27)
					(thickness 0.15)
				)
				(justify left bottom)
				(hide yes)
			)
		)
		(property "Datasheet" ""
			(at 128.27 82.55 0)
			(effects
				(font
					(size 1.27 1.27)
					(thickness 0.15)
				)
				(justify left bottom)
				(hide yes)
			)
		)
		(property "Description" ""
			(at 128.27 82.55 0)
			(effects
				(font
					(size 1.27 1.27)
				)
			)
		)
		(property "Manufacturer" "YAGEO"
			(at 118.11 77.47 0)
			(effects
				(font
					(size 1.27 1.27)
					(thickness 0.15)
				)
				(justify left bottom)
				(hide yes)
			)
		)
		(property "MPN" "CC0201KRX6S5BB104"
			(at 120.65 77.47 0)
			(effects
				(font
					(size 1.27 1.27)
					(thickness 0.15)
				)
				(justify left bottom)
				(hide yes)
			)
		)
		(property "Val" "100n"
			(at 128.905 81.915 90)
			(effects
				(font
					(size 1.27 1.27)
					(thickness 0.15)
				)
				(justify right)
			)
		)
		(property "License" "Apache-2.0"
			(at 151.13 62.23 0)
			(effects
				(font
					(size 1.27 1.27)
					(thickness 0.15)
				)
				(justify left bottom)
				(hide yes)
			)
		)
		(property "Author" "Antmicro"
			(at 153.67 62.23 0)
			(effects
				(font
					(size 1.27 1.27)
					(thickness 0.15)
				)
				(justify left bottom)
				(hide yes)
			)
		)
		(property "Voltage" ""
			(at 156.21 62.23 0)
			(effects
				(font
					(size 1.27 1.27)
				)
				(justify left bottom)
				(hide yes)
			)
		)
		(property "Dielectric" ""
			(at 158.75 62.23 0)
			(effects
				(font
					(size 1.27 1.27)
				)
				(justify left bottom)
				(hide yes)
			)
		)
		(pin "1"
		)
		(pin "2"
		)
		(instances
			(project "lpddr4-testbed"
				(path ""
					(reference "C28")
					(unit 1)
				)
			)
		)
	)
	(symbol
		(lib_id "antmicroCapacitorsmisc:C_100n_0201")
		(at 135.255 82.55 90)
		(unit 1)
		(exclude_from_sim no)
		(in_bom yes)
		(on_board yes)
		(dnp no)
		(property "Reference" "C30"
			(at 135.89 78.105 90)
			(effects
				(font
					(size 1.27 1.27)
					(thickness 0.15)
				)
				(justify right)
			)
		)
		(property "Value" "C_100n_0201"
			(at 139.065 82.55 0)
			(effects
				(font
					(size 1.27 1.27)
					(thickness 0.15)
				)
				(justify left bottom)
				(hide yes)
			)
		)
		(property "Footprint" "antmicro-footprints:C_0201"
			(at 130.175 77.47 0)
			(effects
				(font
					(size 1.27 1.27)
					(thickness 0.15)
				)
				(justify left bottom)
				(hide yes)
			)
		)
		(property "Datasheet" ""
			(at 135.255 82.55 0)
			(effects
				(font
					(size 1.27 1.27)
					(thickness 0.15)
				)
				(justify left bottom)
				(hide yes)
			)
		)
		(property "Description" ""
			(at 135.255 82.55 0)
			(effects
				(font
					(size 1.27 1.27)
				)
			)
		)
		(property "Manufacturer" "YAGEO"
			(at 125.095 77.47 0)
			(effects
				(font
					(size 1.27 1.27)
					(thickness 0.15)
				)
				(justify left bottom)
				(hide yes)
			)
		)
		(property "MPN" "CC0201KRX6S5BB104"
			(at 127.635 77.47 0)
			(effects
				(font
					(size 1.27 1.27)
					(thickness 0.15)
				)
				(justify left bottom)
				(hide yes)
			)
		)
		(property "Val" "100n"
			(at 135.89 81.915 90)
			(effects
				(font
					(size 1.27 1.27)
					(thickness 0.15)
				)
				(justify right)
			)
		)
		(property "License" "Apache-2.0"
			(at 158.115 62.23 0)
			(effects
				(font
					(size 1.27 1.27)
					(thickness 0.15)
				)
				(justify left bottom)
				(hide yes)
			)
		)
		(property "Author" "Antmicro"
			(at 160.655 62.23 0)
			(effects
				(font
					(size 1.27 1.27)
					(thickness 0.15)
				)
				(justify left bottom)
				(hide yes)
			)
		)
		(property "Voltage" ""
			(at 163.195 62.23 0)
			(effects
				(font
					(size 1.27 1.27)
				)
				(justify left bottom)
				(hide yes)
			)
		)
		(property "Dielectric" ""
			(at 165.735 62.23 0)
			(effects
				(font
					(size 1.27 1.27)
				)
				(justify left bottom)
				(hide yes)
			)
		)
		(pin "1"
		)
		(pin "2"
		)
		(instances
			(project "lpddr4-testbed"
				(path ""
					(reference "C30")
					(unit 1)
				)
			)
		)
	)
	(symbol
		(lib_id "antmicroCapacitorsmisc:C_100n_0201")
		(at 142.24 82.55 90)
		(unit 1)
		(exclude_from_sim no)
		(in_bom yes)
		(on_board yes)
		(dnp no)
		(property "Reference" "C32"
			(at 142.875 78.105 90)
			(effects
				(font
					(size 1.27 1.27)
					(thickness 0.15)
				)
				(justify right)
			)
		)
		(property "Value" "C_100n_0201"
			(at 146.05 82.55 0)
			(effects
				(font
					(size 1.27 1.27)
					(thickness 0.15)
				)
				(justify left bottom)
				(hide yes)
			)
		)
		(property "Footprint" "antmicro-footprints:C_0201"
			(at 137.16 77.47 0)
			(effects
				(font
					(size 1.27 1.27)
					(thickness 0.15)
				)
				(justify left bottom)
				(hide yes)
			)
		)
		(property "Datasheet" ""
			(at 142.24 82.55 0)
			(effects
				(font
					(size 1.27 1.27)
					(thickness 0.15)
				)
				(justify left bottom)
				(hide yes)
			)
		)
		(property "Description" ""
			(at 142.24 82.55 0)
			(effects
				(font
					(size 1.27 1.27)
				)
			)
		)
		(property "Manufacturer" "YAGEO"
			(at 132.08 77.47 0)
			(effects
				(font
					(size 1.27 1.27)
					(thickness 0.15)
				)
				(justify left bottom)
				(hide yes)
			)
		)
		(property "MPN" "CC0201KRX6S5BB104"
			(at 134.62 77.47 0)
			(effects
				(font
					(size 1.27 1.27)
					(thickness 0.15)
				)
				(justify left bottom)
				(hide yes)
			)
		)
		(property "Val" "100n"
			(at 142.875 81.915 90)
			(effects
				(font
					(size 1.27 1.27)
					(thickness 0.15)
				)
				(justify right)
			)
		)
		(property "License" "Apache-2.0"
			(at 165.1 62.23 0)
			(effects
				(font
					(size 1.27 1.27)
					(thickness 0.15)
				)
				(justify left bottom)
				(hide yes)
			)
		)
		(property "Author" "Antmicro"
			(at 167.64 62.23 0)
			(effects
				(font
					(size 1.27 1.27)
					(thickness 0.15)
				)
				(justify left bottom)
				(hide yes)
			)
		)
		(property "Voltage" ""
			(at 170.18 62.23 0)
			(effects
				(font
					(size 1.27 1.27)
				)
				(justify left bottom)
				(hide yes)
			)
		)
		(property "Dielectric" ""
			(at 172.72 62.23 0)
			(effects
				(font
					(size 1.27 1.27)
				)
				(justify left bottom)
				(hide yes)
			)
		)
		(pin "1"
		)
		(pin "2"
		)
		(instances
			(project "lpddr4-testbed"
				(path ""
					(reference "C32")
					(unit 1)
				)
			)
		)
	)
	(symbol
		(lib_id "antmicroCapacitorsmisc:C_100n_0201")
		(at 149.225 82.55 90)
		(unit 1)
		(exclude_from_sim no)
		(in_bom yes)
		(on_board yes)
		(dnp no)
		(property "Reference" "C33"
			(at 149.86 78.105 90)
			(effects
				(font
					(size 1.27 1.27)
					(thickness 0.15)
				)
				(justify right)
			)
		)
		(property "Value" "C_100n_0201"
			(at 153.035 82.55 0)
			(effects
				(font
					(size 1.27 1.27)
					(thickness 0.15)
				)
				(justify left bottom)
				(hide yes)
			)
		)
		(property "Footprint" "antmicro-footprints:C_0201"
			(at 144.145 77.47 0)
			(effects
				(font
					(size 1.27 1.27)
					(thickness 0.15)
				)
				(justify left bottom)
				(hide yes)
			)
		)
		(property "Datasheet" ""
			(at 149.225 82.55 0)
			(effects
				(font
					(size 1.27 1.27)
					(thickness 0.15)
				)
				(justify left bottom)
				(hide yes)
			)
		)
		(property "Description" ""
			(at 149.225 82.55 0)
			(effects
				(font
					(size 1.27 1.27)
				)
			)
		)
		(property "Manufacturer" "YAGEO"
			(at 139.065 77.47 0)
			(effects
				(font
					(size 1.27 1.27)
					(thickness 0.15)
				)
				(justify left bottom)
				(hide yes)
			)
		)
		(property "MPN" "CC0201KRX6S5BB104"
			(at 141.605 77.47 0)
			(effects
				(font
					(size 1.27 1.27)
					(thickness 0.15)
				)
				(justify left bottom)
				(hide yes)
			)
		)
		(property "Val" "100n"
			(at 149.86 81.915 90)
			(effects
				(font
					(size 1.27 1.27)
					(thickness 0.15)
				)
				(justify right)
			)
		)
		(property "License" "Apache-2.0"
			(at 172.085 62.23 0)
			(effects
				(font
					(size 1.27 1.27)
					(thickness 0.15)
				)
				(justify left bottom)
				(hide yes)
			)
		)
		(property "Author" "Antmicro"
			(at 174.625 62.23 0)
			(effects
				(font
					(size 1.27 1.27)
					(thickness 0.15)
				)
				(justify left bottom)
				(hide yes)
			)
		)
		(property "Voltage" ""
			(at 177.165 62.23 0)
			(effects
				(font
					(size 1.27 1.27)
				)
				(justify left bottom)
				(hide yes)
			)
		)
		(property "Dielectric" ""
			(at 179.705 62.23 0)
			(effects
				(font
					(size 1.27 1.27)
				)
				(justify left bottom)
				(hide yes)
			)
		)
		(pin "1"
		)
		(pin "2"
		)
		(instances
			(project "lpddr4-testbed"
				(path ""
					(reference "C33")
					(unit 1)
				)
			)
		)
	)
	(symbol
		(lib_id "antmicroCapacitorsmisc:C_100n_0201")
		(at 156.21 82.55 90)
		(unit 1)
		(exclude_from_sim no)
		(in_bom yes)
		(on_board yes)
		(dnp no)
		(property "Reference" "C35"
			(at 156.845 78.105 90)
			(effects
				(font
					(size 1.27 1.27)
					(thickness 0.15)
				)
				(justify right)
			)
		)
		(property "Value" "C_100n_0201"
			(at 160.02 82.55 0)
			(effects
				(font
					(size 1.27 1.27)
					(thickness 0.15)
				)
				(justify left bottom)
				(hide yes)
			)
		)
		(property "Footprint" "antmicro-footprints:C_0201"
			(at 151.13 77.47 0)
			(effects
				(font
					(size 1.27 1.27)
					(thickness 0.15)
				)
				(justify left bottom)
				(hide yes)
			)
		)
		(property "Datasheet" ""
			(at 156.21 82.55 0)
			(effects
				(font
					(size 1.27 1.27)
					(thickness 0.15)
				)
				(justify left bottom)
				(hide yes)
			)
		)
		(property "Description" ""
			(at 156.21 82.55 0)
			(effects
				(font
					(size 1.27 1.27)
				)
			)
		)
		(property "Manufacturer" "YAGEO"
			(at 146.05 77.47 0)
			(effects
				(font
					(size 1.27 1.27)
					(thickness 0.15)
				)
				(justify left bottom)
				(hide yes)
			)
		)
		(property "MPN" "CC0201KRX6S5BB104"
			(at 148.59 77.47 0)
			(effects
				(font
					(size 1.27 1.27)
					(thickness 0.15)
				)
				(justify left bottom)
				(hide yes)
			)
		)
		(property "Val" "100n"
			(at 156.845 81.915 90)
			(effects
				(font
					(size 1.27 1.27)
					(thickness 0.15)
				)
				(justify right)
			)
		)
		(property "License" "Apache-2.0"
			(at 179.07 62.23 0)
			(effects
				(font
					(size 1.27 1.27)
					(thickness 0.15)
				)
				(justify left bottom)
				(hide yes)
			)
		)
		(property "Author" "Antmicro"
			(at 181.61 62.23 0)
			(effects
				(font
					(size 1.27 1.27)
					(thickness 0.15)
				)
				(justify left bottom)
				(hide yes)
			)
		)
		(property "Voltage" ""
			(at 184.15 62.23 0)
			(effects
				(font
					(size 1.27 1.27)
				)
				(justify left bottom)
				(hide yes)
			)
		)
		(property "Dielectric" ""
			(at 186.69 62.23 0)
			(effects
				(font
					(size 1.27 1.27)
				)
				(justify left bottom)
				(hide yes)
			)
		)
		(pin "1"
		)
		(pin "2"
		)
		(instances
			(project "lpddr4-testbed"
				(path ""
					(reference "C35")
					(unit 1)
				)
			)
		)
	)
	(symbol
		(lib_id "antmicroCapacitorsmisc:C_100n_0201")
		(at 163.195 82.55 90)
		(unit 1)
		(exclude_from_sim no)
		(in_bom yes)
		(on_board yes)
		(dnp no)
		(property "Reference" "C36"
			(at 163.83 78.105 90)
			(effects
				(font
					(size 1.27 1.27)
					(thickness 0.15)
				)
				(justify right)
			)
		)
		(property "Value" "C_100n_0201"
			(at 167.005 82.55 0)
			(effects
				(font
					(size 1.27 1.27)
					(thickness 0.15)
				)
				(justify left bottom)
				(hide yes)
			)
		)
		(property "Footprint" "antmicro-footprints:C_0201"
			(at 158.115 77.47 0)
			(effects
				(font
					(size 1.27 1.27)
					(thickness 0.15)
				)
				(justify left bottom)
				(hide yes)
			)
		)
		(property "Datasheet" ""
			(at 163.195 82.55 0)
			(effects
				(font
					(size 1.27 1.27)
					(thickness 0.15)
				)
				(justify left bottom)
				(hide yes)
			)
		)
		(property "Description" ""
			(at 163.195 82.55 0)
			(effects
				(font
					(size 1.27 1.27)
				)
			)
		)
		(property "Manufacturer" "YAGEO"
			(at 153.035 77.47 0)
			(effects
				(font
					(size 1.27 1.27)
					(thickness 0.15)
				)
				(justify left bottom)
				(hide yes)
			)
		)
		(property "MPN" "CC0201KRX6S5BB104"
			(at 155.575 77.47 0)
			(effects
				(font
					(size 1.27 1.27)
					(thickness 0.15)
				)
				(justify left bottom)
				(hide yes)
			)
		)
		(property "Val" "100n"
			(at 163.83 81.915 90)
			(effects
				(font
					(size 1.27 1.27)
					(thickness 0.15)
				)
				(justify right)
			)
		)
		(property "License" "Apache-2.0"
			(at 186.055 62.23 0)
			(effects
				(font
					(size 1.27 1.27)
					(thickness 0.15)
				)
				(justify left bottom)
				(hide yes)
			)
		)
		(property "Author" "Antmicro"
			(at 188.595 62.23 0)
			(effects
				(font
					(size 1.27 1.27)
					(thickness 0.15)
				)
				(justify left bottom)
				(hide yes)
			)
		)
		(property "Voltage" ""
			(at 191.135 62.23 0)
			(effects
				(font
					(size 1.27 1.27)
				)
				(justify left bottom)
				(hide yes)
			)
		)
		(property "Dielectric" ""
			(at 193.675 62.23 0)
			(effects
				(font
					(size 1.27 1.27)
				)
				(justify left bottom)
				(hide yes)
			)
		)
		(pin "1"
		)
		(pin "2"
		)
		(instances
			(project "lpddr4-testbed"
				(path ""
					(reference "C36")
					(unit 1)
				)
			)
		)
	)
	(symbol
		(lib_id "antmicroResistors0402:R_10k_0402")
		(at 189.865 217.17 0)
		(mirror x)
		(unit 1)
		(exclude_from_sim no)
		(in_bom yes)
		(on_board yes)
		(dnp no)
		(property "Reference" "R4"
			(at 196.215 215.9 0)
			(effects
				(font
					(size 1.27 1.27)
					(thickness 0.15)
				)
			)
		)
		(property "Value" "R_10k_0402"
			(at 189.865 213.36 0)
			(effects
				(font
					(size 1.27 1.27)
					(thickness 0.15)
				)
				(justify left bottom)
				(hide yes)
			)
		)
		(property "Footprint" "antmicro-footprints:R_0402_1005Metric"
			(at 194.945 222.25 0)
			(effects
				(font
					(size 1.27 1.27)
					(thickness 0.15)
				)
				(justify left bottom)
				(hide yes)
			)
		)
		(property "Datasheet" ""
			(at 189.865 217.17 0)
			(effects
				(font
					(size 1.27 1.27)
					(thickness 0.15)
				)
				(justify left bottom)
				(hide yes)
			)
		)
		(property "Description" ""
			(at 189.865 217.17 0)
			(effects
				(font
					(size 1.27 1.27)
				)
			)
		)
		(property "Manufacturer" "VISHAY"
			(at 194.945 227.33 0)
			(effects
				(font
					(size 1.27 1.27)
					(thickness 0.15)
				)
				(justify left bottom)
				(hide yes)
			)
		)
		(property "MPN" "CRCW040210K0FKEDHP"
			(at 194.945 224.79 0)
			(effects
				(font
					(size 1.27 1.27)
					(thickness 0.15)
				)
				(justify left bottom)
				(hide yes)
			)
		)
		(property "Val" "10k"
			(at 187.96 215.9 0)
			(effects
				(font
					(size 1.27 1.27)
					(thickness 0.15)
				)
			)
		)
		(property "License" "Apache-2.0"
			(at 210.185 191.77 0)
			(effects
				(font
					(size 1.27 1.27)
					(thickness 0.15)
				)
				(justify left bottom)
				(hide yes)
			)
		)
		(property "Author" "Antmicro"
			(at 210.185 189.23 0)
			(effects
				(font
					(size 1.27 1.27)
					(thickness 0.15)
				)
				(justify left bottom)
				(hide yes)
			)
		)
		(property "Tolerance" "1%"
			(at 210.185 207.01 0)
			(effects
				(font
					(size 1.27 1.27)
				)
				(justify left bottom)
				(hide yes)
			)
		)
		(pin "1"
		)
		(pin "2"
		)
		(instances
			(project "lpddr4-testbed"
				(path ""
					(reference "R4")
					(unit 1)
				)
			)
		)
	)
	(symbol
		(lib_id "antmicroResistors0402:R_10k_0402")
		(at 187.96 62.23 90)
		(mirror x)
		(unit 1)
		(exclude_from_sim no)
		(in_bom yes)
		(on_board yes)
		(dnp no)
		(property "Reference" "R5"
			(at 189.23 63.5 90)
			(effects
				(font
					(size 1.27 1.27)
					(thickness 0.15)
				)
				(justify right)
			)
		)
		(property "Value" "R_10k_0402"
			(at 191.77 62.23 0)
			(effects
				(font
					(size 1.27 1.27)
					(thickness 0.15)
				)
				(justify left bottom)
				(hide yes)
			)
		)
		(property "Footprint" "antmicro-footprints:R_0402_1005Metric"
			(at 182.88 67.31 0)
			(effects
				(font
					(size 1.27 1.27)
					(thickness 0.15)
				)
				(justify left bottom)
				(hide yes)
			)
		)
		(property "Datasheet" ""
			(at 187.96 62.23 0)
			(effects
				(font
					(size 1.27 1.27)
					(thickness 0.15)
				)
				(justify left bottom)
				(hide yes)
			)
		)
		(property "Description" ""
			(at 187.96 62.23 0)
			(effects
				(font
					(size 1.27 1.27)
				)
			)
		)
		(property "Manufacturer" "VISHAY"
			(at 177.8 67.31 0)
			(effects
				(font
					(size 1.27 1.27)
					(thickness 0.15)
				)
				(justify left bottom)
				(hide yes)
			)
		)
		(property "MPN" "CRCW040210K0FKEDHP"
			(at 180.34 67.31 0)
			(effects
				(font
					(size 1.27 1.27)
					(thickness 0.15)
				)
				(justify left bottom)
				(hide yes)
			)
		)
		(property "Val" "10k"
			(at 189.23 66.04 90)
			(effects
				(font
					(size 1.27 1.27)
					(thickness 0.15)
				)
				(justify right)
			)
		)
		(property "License" "Apache-2.0"
			(at 213.36 82.55 0)
			(effects
				(font
					(size 1.27 1.27)
					(thickness 0.15)
				)
				(justify left bottom)
				(hide yes)
			)
		)
		(property "Author" "Antmicro"
			(at 215.9 82.55 0)
			(effects
				(font
					(size 1.27 1.27)
					(thickness 0.15)
				)
				(justify left bottom)
				(hide yes)
			)
		)
		(property "Tolerance" "1%"
			(at 198.12 82.55 0)
			(effects
				(font
					(size 1.27 1.27)
				)
				(justify left bottom)
				(hide yes)
			)
		)
		(pin "1"
		)
		(pin "2"
		)
		(instances
			(project "lpddr4-testbed"
				(path ""
					(reference "R5")
					(unit 1)
				)
			)
		)
	)
	(symbol
		(lib_id "antmicroResistors0402:R_0R_0402")
		(at 183.515 68.58 0)
		(mirror y)
		(unit 1)
		(exclude_from_sim no)
		(in_bom yes)
		(on_board yes)
		(dnp no)
		(property "Reference" "R7"
			(at 177.165 67.31 0)
			(effects
				(font
					(size 1.27 1.27)
					(thickness 0.15)
				)
			)
		)
		(property "Value" "R_0R_0402"
			(at 183.515 72.39 0)
			(effects
				(font
					(size 1.27 1.27)
					(thickness 0.15)
				)
				(justify left bottom)
				(hide yes)
			)
		)
		(property "Footprint" "antmicro-footprints:R_0402_1005Metric"
			(at 178.435 63.5 0)
			(effects
				(font
					(size 1.27 1.27)
					(thickness 0.15)
				)
				(justify left bottom)
				(hide yes)
			)
		)
		(property "Datasheet" ""
			(at 183.515 68.58 0)
			(effects
				(font
					(size 1.27 1.27)
					(thickness 0.15)
				)
				(justify left bottom)
				(hide yes)
			)
		)
		(property "Description" ""
			(at 183.515 68.58 0)
			(effects
				(font
					(size 1.27 1.27)
				)
			)
		)
		(property "Manufacturer" "PANASONIC"
			(at 178.435 58.42 0)
			(effects
				(font
					(size 1.27 1.27)
					(thickness 0.15)
				)
				(justify left bottom)
				(hide yes)
			)
		)
		(property "MPN" "ERJ2GE0R00X"
			(at 178.435 60.96 0)
			(effects
				(font
					(size 1.27 1.27)
					(thickness 0.15)
				)
				(justify left bottom)
				(hide yes)
			)
		)
		(property "Val" "0R"
			(at 184.785 67.31 0)
			(effects
				(font
					(size 1.27 1.27)
					(thickness 0.15)
				)
			)
		)
		(property "License" "Apache-2.0"
			(at 163.195 93.98 0)
			(effects
				(font
					(size 1.27 1.27)
					(thickness 0.15)
				)
				(justify left bottom)
				(hide yes)
			)
		)
		(property "Author" "Antmicro"
			(at 163.195 96.52 0)
			(effects
				(font
					(size 1.27 1.27)
					(thickness 0.15)
				)
				(justify left bottom)
				(hide yes)
			)
		)
		(property "Tolerance" "~"
			(at 163.195 78.74 0)
			(effects
				(font
					(size 1.27 1.27)
				)
				(justify left bottom)
				(hide yes)
			)
		)
		(property "Current" "1A"
			(at 163.195 99.06 0)
			(effects
				(font
					(size 1.27 1.27)
					(thickness 0.15)
				)
				(justify left bottom)
				(hide yes)
			)
		)
		(pin "1"
		)
		(pin "2"
		)
		(instances
			(project "lpddr4-testbed"
				(path ""
					(reference "R7")
					(unit 1)
				)
			)
		)
	)
	(symbol
		(lib_id "antmicroResistors0402:R_240R_0402")
		(at 189.23 121.285 90)
		(mirror x)
		(unit 1)
		(exclude_from_sim no)
		(in_bom yes)
		(on_board yes)
		(dnp no)
		(property "Reference" "R6"
			(at 190.5 122.555 90)
			(effects
				(font
					(size 1.27 1.27)
					(thickness 0.15)
				)
				(justify right)
			)
		)
		(property "Value" "R_240R_0402"
			(at 193.04 121.285 0)
			(effects
				(font
					(size 1.27 1.27)
					(thickness 0.15)
				)
				(justify left bottom)
				(hide yes)
			)
		)
		(property "Footprint" "antmicro-footprints:R_0402_1005Metric"
			(at 184.15 126.365 0)
			(effects
				(font
					(size 1.27 1.27)
					(thickness 0.15)
				)
				(justify left bottom)
				(hide yes)
			)
		)
		(property "Datasheet" ""
			(at 189.23 121.285 0)
			(effects
				(font
					(size 1.27 1.27)
					(thickness 0.15)
				)
				(justify left bottom)
				(hide yes)
			)
		)
		(property "Description" ""
			(at 189.23 121.285 0)
			(effects
				(font
					(size 1.27 1.27)
				)
			)
		)
		(property "Manufacturer" "PANASONIC"
			(at 179.07 126.365 0)
			(effects
				(font
					(size 1.27 1.27)
					(thickness 0.15)
				)
				(justify left bottom)
				(hide yes)
			)
		)
		(property "MPN" "ERJ2GEJ241X"
			(at 181.61 126.365 0)
			(effects
				(font
					(size 1.27 1.27)
					(thickness 0.15)
				)
				(justify left bottom)
				(hide yes)
			)
		)
		(property "Val" "240R"
			(at 190.5 125.095 90)
			(effects
				(font
					(size 1.27 1.27)
					(thickness 0.15)
				)
				(justify right)
			)
		)
		(property "License" "Apache-2.0"
			(at 214.63 141.605 0)
			(effects
				(font
					(size 1.27 1.27)
					(thickness 0.15)
				)
				(justify left bottom)
				(hide yes)
			)
		)
		(property "Author" "Antmicro"
			(at 217.17 141.605 0)
			(effects
				(font
					(size 1.27 1.27)
					(thickness 0.15)
				)
				(justify left bottom)
				(hide yes)
			)
		)
		(property "Tolerance" "1%"
			(at 199.39 141.605 0)
			(effects
				(font
					(size 1.27 1.27)
				)
				(justify left bottom)
				(hide yes)
			)
		)
		(pin "1"
		)
		(pin "2"
		)
		(instances
			(project "lpddr4-testbed"
				(path ""
					(reference "R6")
					(unit 1)
				)
			)
		)
	)
	(symbol
		(lib_id "antmicropower:GND")
		(at 189.23 127 0)
		(mirror y)
		(unit 1)
		(exclude_from_sim no)
		(in_bom yes)
		(on_board yes)
		(dnp no)
		(property "Reference" "#PWR0105"
			(at 189.23 133.35 0)
			(effects
				(font
					(size 1.27 1.27)
				)
				(hide yes)
			)
		)
		(property "Value" "GND"
			(at 189.23 130.81 0)
			(effects
				(font
					(size 1.27 1.27)
				)
			)
		)
		(property "Footprint" ""
			(at 189.23 127 0)
			(effects
				(font
					(size 1.27 1.27)
				)
				(hide yes)
			)
		)
		(property "Datasheet" ""
			(at 189.23 127 0)
			(effects
				(font
					(size 1.27 1.27)
				)
				(hide yes)
			)
		)
		(property "Description" ""
			(at 189.23 127 0)
			(effects
				(font
					(size 1.27 1.27)
				)
			)
		)
		(pin "1"
		)
		(instances
			(project "lpddr4-testbed"
				(path ""
					(reference "#PWR0105")
					(unit 1)
				)
			)
		)
	)
	(symbol
		(lib_id "antmicropower:GND")
		(at 196.85 127 0)
		(unit 1)
		(exclude_from_sim no)
		(in_bom yes)
		(on_board yes)
		(dnp no)
		(property "Reference" "#PWR023"
			(at 196.85 133.35 0)
			(effects
				(font
					(size 1.27 1.27)
				)
				(hide yes)
			)
		)
		(property "Value" "GND"
			(at 196.85 130.81 0)
			(effects
				(font
					(size 1.27 1.27)
				)
			)
		)
		(property "Footprint" ""
			(at 196.85 127 0)
			(effects
				(font
					(size 1.27 1.27)
				)
				(hide yes)
			)
		)
		(property "Datasheet" ""
			(at 196.85 127 0)
			(effects
				(font
					(size 1.27 1.27)
				)
				(hide yes)
			)
		)
		(property "Description" ""
			(at 196.85 127 0)
			(effects
				(font
					(size 1.27 1.27)
				)
			)
		)
		(pin "1"
		)
		(instances
			(project "lpddr4-testbed"
				(path ""
					(reference "#PWR023")
					(unit 1)
				)
			)
		)
	)
	(symbol
		(lib_id "antmicropower:GND")
		(at 196.85 226.06 0)
		(unit 1)
		(exclude_from_sim no)
		(in_bom yes)
		(on_board yes)
		(dnp no)
		(property "Reference" "#PWR039"
			(at 196.85 232.41 0)
			(effects
				(font
					(size 1.27 1.27)
				)
				(hide yes)
			)
		)
		(property "Value" "GND"
			(at 196.977 230.4542 0)
			(effects
				(font
					(size 1.27 1.27)
				)
			)
		)
		(property "Footprint" ""
			(at 196.85 226.06 0)
			(effects
				(font
					(size 1.27 1.27)
				)
				(hide yes)
			)
		)
		(property "Datasheet" ""
			(at 196.85 226.06 0)
			(effects
				(font
					(size 1.27 1.27)
				)
				(hide yes)
			)
		)
		(property "Description" ""
			(at 196.85 226.06 0)
			(effects
				(font
					(size 1.27 1.27)
				)
			)
		)
		(pin "1"
		)
		(instances
			(project "lpddr4-testbed"
				(path ""
					(reference "#PWR039")
					(unit 1)
				)
			)
		)
	)
	(symbol
		(lib_id "antmicroMemory:MT53E1G32D2NP-046")
		(at 198.12 66.04 0)
		(unit 1)
		(exclude_from_sim no)
		(in_bom yes)
		(on_board yes)
		(dnp no)
		(fields_autoplaced yes)
		(property "Reference" "U1"
			(at 218.44 58.42 0)
			(effects
				(font
					(size 1.27 1.27)
					(thickness 0.15)
				)
			)
		)
		(property "Value" "MT53E1G32D2NP-046"
			(at 198.12 108.712 0)
			(effects
				(font
					(size 1.27 1.27)
					(thickness 0.15)
				)
				(justify left bottom)
				(hide yes)
			)
		)
		(property "Footprint" "antmicro-footprints:BGA-264-200_10x14.5mm_Layout12x22_P0.8x0.65mm"
			(at 199.39 114.3 0)
			(effects
				(font
					(size 1.27 1.27)
					(thickness 0.15)
				)
				(justify left bottom)
				(hide yes)
			)
		)
		(property "Datasheet" "https://www.micron.com/products/dram/lpdram/part-catalog/mt53e1g32d2np-046-wt"
			(at 195.58 96.52 0)
			(effects
				(font
					(size 1.27 1.27)
					(thickness 0.15)
				)
				(justify left bottom)
				(hide yes)
			)
		)
		(property "Description" ""
			(at 198.12 66.04 0)
			(effects
				(font
					(size 1.27 1.27)
				)
			)
		)
		(property "Manufacturer" "Micron Technology"
			(at 218.44 58.42 0)
			(effects
				(font
					(size 1.27 1.27)
					(thickness 0.15)
				)
				(justify left bottom)
				(hide yes)
			)
		)
		(property "MPN" "MT53E1G32D2NP-046 WT:A"
			(at 218.44 60.96 0)
			(effects
				(font
					(size 1.27 1.27)
					(thickness 0.15)
				)
			)
		)
		(property "Author" "Antmicro"
			(at 254 81.28 0)
			(effects
				(font
					(size 1.27 1.27)
					(thickness 0.15)
				)
				(justify left bottom)
				(hide yes)
			)
		)
		(property "License" "Apache-2.0"
			(at 254 83.82 0)
			(effects
				(font
					(size 1.27 1.27)
					(thickness 0.15)
				)
				(justify left bottom)
				(hide yes)
			)
		)
		(pin "A1"
		)
		(pin "A10"
		)
		(pin "A11"
		)
		(pin "A12"
		)
		(pin "A2"
		)
		(pin "A3"
		)
		(pin "A4"
		)
		(pin "A5"
		)
		(pin "A9"
		)
		(pin "B1"
		)
		(pin "B10"
		)
		(pin "B11"
		)
		(pin "B12"
		)
		(pin "B2"
		)
		(pin "B3"
		)
		(pin "B4"
		)
		(pin "B5"
		)
		(pin "B8"
		)
		(pin "B9"
		)
		(pin "C1"
		)
		(pin "C10"
		)
		(pin "C11"
		)
		(pin "C12"
		)
		(pin "C2"
		)
		(pin "C3"
		)
		(pin "C4"
		)
		(pin "C5"
		)
		(pin "C8"
		)
		(pin "C9"
		)
		(pin "D1"
		)
		(pin "D10"
		)
		(pin "D11"
		)
		(pin "D12"
		)
		(pin "D2"
		)
		(pin "D3"
		)
		(pin "D4"
		)
		(pin "D5"
		)
		(pin "D8"
		)
		(pin "D9"
		)
		(pin "E1"
		)
		(pin "E10"
		)
		(pin "E11"
		)
		(pin "E12"
		)
		(pin "E2"
		)
		(pin "E3"
		)
		(pin "E4"
		)
		(pin "E5"
		)
		(pin "E8"
		)
		(pin "E9"
		)
		(pin "F1"
		)
		(pin "F10"
		)
		(pin "F11"
		)
		(pin "F12"
		)
		(pin "F2"
		)
		(pin "F3"
		)
		(pin "F4"
		)
		(pin "F5"
		)
		(pin "F8"
		)
		(pin "F9"
		)
		(pin "G1"
		)
		(pin "G10"
		)
		(pin "G12"
		)
		(pin "G2"
		)
		(pin "G3"
		)
		(pin "G4"
		)
		(pin "G5"
		)
		(pin "G8"
		)
		(pin "G9"
		)
		(pin "H1"
		)
		(pin "H10"
		)
		(pin "H11"
		)
		(pin "H12"
		)
		(pin "H2"
		)
		(pin "H3"
		)
		(pin "H4"
		)
		(pin "H5"
		)
		(pin "H8"
		)
		(pin "H9"
		)
		(pin "J1"
		)
		(pin "J10"
		)
		(pin "J11"
		)
		(pin "J12"
		)
		(pin "J2"
		)
		(pin "J3"
		)
		(pin "J4"
		)
		(pin "J5"
		)
		(pin "J8"
		)
		(pin "J9"
		)
		(pin "K1"
		)
		(pin "K10"
		)
		(pin "K11"
		)
		(pin "K12"
		)
		(pin "K2"
		)
		(pin "K3"
		)
		(pin "K4"
		)
		(pin "K5"
		)
		(pin "K8"
		)
		(pin "K9"
		)
		(pin "T11"
		)
		(pin "A8"
		)
		(pin "AA1"
		)
		(pin "AA10"
		)
		(pin "AA11"
		)
		(pin "AA12"
		)
		(pin "AA2"
		)
		(pin "AA3"
		)
		(pin "AA4"
		)
		(pin "AA5"
		)
		(pin "AA8"
		)
		(pin "AA9"
		)
		(pin "AB1"
		)
		(pin "AB10"
		)
		(pin "AB11"
		)
		(pin "AB12"
		)
		(pin "AB2"
		)
		(pin "AB3"
		)
		(pin "AB4"
		)
		(pin "AB5"
		)
		(pin "AB8"
		)
		(pin "AB9"
		)
		(pin "G11"
		)
		(pin "N1"
		)
		(pin "N10"
		)
		(pin "N11"
		)
		(pin "N12"
		)
		(pin "N2"
		)
		(pin "N3"
		)
		(pin "N4"
		)
		(pin "N5"
		)
		(pin "N8"
		)
		(pin "N9"
		)
		(pin "P1"
		)
		(pin "P10"
		)
		(pin "P11"
		)
		(pin "P12"
		)
		(pin "P2"
		)
		(pin "P3"
		)
		(pin "P4"
		)
		(pin "P5"
		)
		(pin "P8"
		)
		(pin "P9"
		)
		(pin "R1"
		)
		(pin "R10"
		)
		(pin "R11"
		)
		(pin "R12"
		)
		(pin "R2"
		)
		(pin "R3"
		)
		(pin "R4"
		)
		(pin "R5"
		)
		(pin "R8"
		)
		(pin "R9"
		)
		(pin "T1"
		)
		(pin "T10"
		)
		(pin "T12"
		)
		(pin "T2"
		)
		(pin "T3"
		)
		(pin "T4"
		)
		(pin "T5"
		)
		(pin "T8"
		)
		(pin "T9"
		)
		(pin "U1"
		)
		(pin "U10"
		)
		(pin "U11"
		)
		(pin "U12"
		)
		(pin "U2"
		)
		(pin "U3"
		)
		(pin "U4"
		)
		(pin "U5"
		)
		(pin "U8"
		)
		(pin "U9"
		)
		(pin "V1"
		)
		(pin "V10"
		)
		(pin "V11"
		)
		(pin "V12"
		)
		(pin "V2"
		)
		(pin "V3"
		)
		(pin "V4"
		)
		(pin "V5"
		)
		(pin "V8"
		)
		(pin "V9"
		)
		(pin "W1"
		)
		(pin "W10"
		)
		(pin "W11"
		)
		(pin "W12"
		)
		(pin "W2"
		)
		(pin "W3"
		)
		(pin "W4"
		)
		(pin "W5"
		)
		(pin "W8"
		)
		(pin "W9"
		)
		(pin "Y1"
		)
		(pin "Y10"
		)
		(pin "Y11"
		)
		(pin "Y12"
		)
		(pin "Y2"
		)
		(pin "Y3"
		)
		(pin "Y4"
		)
		(pin "Y5"
		)
		(pin "Y8"
		)
		(pin "Y9"
		)
		(instances
			(project "lpddr4-testbed"
				(path ""
					(reference "U1")
					(unit 1)
				)
			)
		)
	)
	(symbol
		(lib_id "antmicroMemory:MT53E1G32D2NP-046")
		(at 198.12 166.37 0)
		(unit 2)
		(exclude_from_sim no)
		(in_bom yes)
		(on_board yes)
		(dnp no)
		(fields_autoplaced yes)
		(property "Reference" "U1"
			(at 218.44 158.75 0)
			(effects
				(font
					(size 1.27 1.27)
					(thickness 0.15)
				)
			)
		)
		(property "Value" "MT53E1G32D2NP-046"
			(at 198.12 209.042 0)
			(effects
				(font
					(size 1.27 1.27)
					(thickness 0.15)
				)
				(justify left bottom)
				(hide yes)
			)
		)
		(property "Footprint" "antmicro-footprints:BGA-264-200_10x14.5mm_Layout12x22_P0.8x0.65mm"
			(at 199.39 214.63 0)
			(effects
				(font
					(size 1.27 1.27)
					(thickness 0.15)
				)
				(justify left bottom)
				(hide yes)
			)
		)
		(property "Datasheet" "https://www.micron.com/products/dram/lpdram/part-catalog/mt53e1g32d2np-046-wt"
			(at 195.58 196.85 0)
			(effects
				(font
					(size 1.27 1.27)
					(thickness 0.15)
				)
				(justify left bottom)
				(hide yes)
			)
		)
		(property "Description" ""
			(at 198.12 166.37 0)
			(effects
				(font
					(size 1.27 1.27)
				)
			)
		)
		(property "Manufacturer" "Micron Technology"
			(at 220.4594 242.57 0)
			(effects
				(font
					(size 1.27 1.27)
					(thickness 0.15)
				)
				(justify left bottom)
				(hide yes)
			)
		)
		(property "MPN" "MT53E1G32D2NP-046 WT:A"
			(at 218.44 161.29 0)
			(effects
				(font
					(size 1.27 1.27)
					(thickness 0.15)
				)
			)
		)
		(property "Author" "Antmicro"
			(at 254 181.61 0)
			(effects
				(font
					(size 1.27 1.27)
					(thickness 0.15)
				)
				(justify left bottom)
				(hide yes)
			)
		)
		(property "License" "Apache-2.0"
			(at 254 184.15 0)
			(effects
				(font
					(size 1.27 1.27)
					(thickness 0.15)
				)
				(justify left bottom)
				(hide yes)
			)
		)
		(pin "A1"
		)
		(pin "A10"
		)
		(pin "A11"
		)
		(pin "A12"
		)
		(pin "A2"
		)
		(pin "A3"
		)
		(pin "A4"
		)
		(pin "A5"
		)
		(pin "A9"
		)
		(pin "B1"
		)
		(pin "B10"
		)
		(pin "B11"
		)
		(pin "B12"
		)
		(pin "B2"
		)
		(pin "B3"
		)
		(pin "B4"
		)
		(pin "B5"
		)
		(pin "B8"
		)
		(pin "B9"
		)
		(pin "C1"
		)
		(pin "C10"
		)
		(pin "C11"
		)
		(pin "C12"
		)
		(pin "C2"
		)
		(pin "C3"
		)
		(pin "C4"
		)
		(pin "C5"
		)
		(pin "C8"
		)
		(pin "C9"
		)
		(pin "D1"
		)
		(pin "D10"
		)
		(pin "D11"
		)
		(pin "D12"
		)
		(pin "D2"
		)
		(pin "D3"
		)
		(pin "D4"
		)
		(pin "D5"
		)
		(pin "D8"
		)
		(pin "D9"
		)
		(pin "E1"
		)
		(pin "E10"
		)
		(pin "E11"
		)
		(pin "E12"
		)
		(pin "E2"
		)
		(pin "E3"
		)
		(pin "E4"
		)
		(pin "E5"
		)
		(pin "E8"
		)
		(pin "E9"
		)
		(pin "F1"
		)
		(pin "F10"
		)
		(pin "F11"
		)
		(pin "F12"
		)
		(pin "F2"
		)
		(pin "F3"
		)
		(pin "F4"
		)
		(pin "F5"
		)
		(pin "F8"
		)
		(pin "F9"
		)
		(pin "G1"
		)
		(pin "G10"
		)
		(pin "G12"
		)
		(pin "G2"
		)
		(pin "G3"
		)
		(pin "G4"
		)
		(pin "G5"
		)
		(pin "G8"
		)
		(pin "G9"
		)
		(pin "H1"
		)
		(pin "H10"
		)
		(pin "H11"
		)
		(pin "H12"
		)
		(pin "H2"
		)
		(pin "H3"
		)
		(pin "H4"
		)
		(pin "H5"
		)
		(pin "H8"
		)
		(pin "H9"
		)
		(pin "J1"
		)
		(pin "J10"
		)
		(pin "J11"
		)
		(pin "J12"
		)
		(pin "J2"
		)
		(pin "J3"
		)
		(pin "J4"
		)
		(pin "J5"
		)
		(pin "J8"
		)
		(pin "J9"
		)
		(pin "K1"
		)
		(pin "K10"
		)
		(pin "K11"
		)
		(pin "K12"
		)
		(pin "K2"
		)
		(pin "K3"
		)
		(pin "K4"
		)
		(pin "K5"
		)
		(pin "K8"
		)
		(pin "K9"
		)
		(pin "T11"
		)
		(pin "A8"
		)
		(pin "AA1"
		)
		(pin "AA10"
		)
		(pin "AA11"
		)
		(pin "AA12"
		)
		(pin "AA2"
		)
		(pin "AA3"
		)
		(pin "AA4"
		)
		(pin "AA5"
		)
		(pin "AA8"
		)
		(pin "AA9"
		)
		(pin "AB1"
		)
		(pin "AB10"
		)
		(pin "AB11"
		)
		(pin "AB12"
		)
		(pin "AB2"
		)
		(pin "AB3"
		)
		(pin "AB4"
		)
		(pin "AB5"
		)
		(pin "AB8"
		)
		(pin "AB9"
		)
		(pin "G11"
		)
		(pin "N1"
		)
		(pin "N10"
		)
		(pin "N11"
		)
		(pin "N12"
		)
		(pin "N2"
		)
		(pin "N3"
		)
		(pin "N4"
		)
		(pin "N5"
		)
		(pin "N8"
		)
		(pin "N9"
		)
		(pin "P1"
		)
		(pin "P10"
		)
		(pin "P11"
		)
		(pin "P12"
		)
		(pin "P2"
		)
		(pin "P3"
		)
		(pin "P4"
		)
		(pin "P5"
		)
		(pin "P8"
		)
		(pin "P9"
		)
		(pin "R1"
		)
		(pin "R10"
		)
		(pin "R11"
		)
		(pin "R12"
		)
		(pin "R2"
		)
		(pin "R3"
		)
		(pin "R4"
		)
		(pin "R5"
		)
		(pin "R8"
		)
		(pin "R9"
		)
		(pin "T1"
		)
		(pin "T10"
		)
		(pin "T12"
		)
		(pin "T2"
		)
		(pin "T3"
		)
		(pin "T4"
		)
		(pin "T5"
		)
		(pin "T8"
		)
		(pin "T9"
		)
		(pin "U1"
		)
		(pin "U10"
		)
		(pin "U11"
		)
		(pin "U12"
		)
		(pin "U2"
		)
		(pin "U3"
		)
		(pin "U4"
		)
		(pin "U5"
		)
		(pin "U8"
		)
		(pin "U9"
		)
		(pin "V1"
		)
		(pin "V10"
		)
		(pin "V11"
		)
		(pin "V12"
		)
		(pin "V2"
		)
		(pin "V3"
		)
		(pin "V4"
		)
		(pin "V5"
		)
		(pin "V8"
		)
		(pin "V9"
		)
		(pin "W1"
		)
		(pin "W10"
		)
		(pin "W11"
		)
		(pin "W12"
		)
		(pin "W2"
		)
		(pin "W3"
		)
		(pin "W4"
		)
		(pin "W5"
		)
		(pin "W8"
		)
		(pin "W9"
		)
		(pin "Y1"
		)
		(pin "Y10"
		)
		(pin "Y11"
		)
		(pin "Y12"
		)
		(pin "Y2"
		)
		(pin "Y3"
		)
		(pin "Y4"
		)
		(pin "Y5"
		)
		(pin "Y8"
		)
		(pin "Y9"
		)
		(instances
			(project "lpddr4-testbed"
				(path ""
					(reference "U1")
					(unit 2)
				)
			)
		)
	)
	(symbol
		(lib_id "antmicropower:GND")
		(at 128.27 83.185 0)
		(unit 1)
		(exclude_from_sim no)
		(in_bom yes)
		(on_board yes)
		(dnp no)
		(property "Reference" "#PWR0142"
			(at 128.27 89.535 0)
			(effects
				(font
					(size 1.27 1.27)
				)
				(hide yes)
			)
		)
		(property "Value" "GND"
			(at 128.397 87.5792 0)
			(effects
				(font
					(size 1.27 1.27)
				)
			)
		)
		(property "Footprint" ""
			(at 128.27 83.185 0)
			(effects
				(font
					(size 1.27 1.27)
				)
				(hide yes)
			)
		)
		(property "Datasheet" ""
			(at 128.27 83.185 0)
			(effects
				(font
					(size 1.27 1.27)
				)
				(hide yes)
			)
		)
		(property "Description" ""
			(at 128.27 83.185 0)
			(effects
				(font
					(size 1.27 1.27)
				)
			)
		)
		(pin "1"
		)
		(instances
			(project "lpddr4-testbed"
				(path ""
					(reference "#PWR0142")
					(unit 1)
				)
			)
		)
	)
	(symbol
		(lib_id "antmicropower:GND")
		(at 114.3 153.035 0)
		(unit 1)
		(exclude_from_sim no)
		(in_bom yes)
		(on_board yes)
		(dnp no)
		(property "Reference" "#PWR0132"
			(at 114.3 159.385 0)
			(effects
				(font
					(size 1.27 1.27)
				)
				(hide yes)
			)
		)
		(property "Value" "GND"
			(at 114.427 157.4292 0)
			(effects
				(font
					(size 1.27 1.27)
				)
			)
		)
		(property "Footprint" ""
			(at 114.3 153.035 0)
			(effects
				(font
					(size 1.27 1.27)
				)
				(hide yes)
			)
		)
		(property "Datasheet" ""
			(at 114.3 153.035 0)
			(effects
				(font
					(size 1.27 1.27)
				)
				(hide yes)
			)
		)
		(property "Description" ""
			(at 114.3 153.035 0)
			(effects
				(font
					(size 1.27 1.27)
				)
			)
		)
		(pin "1"
		)
		(instances
			(project "lpddr4-testbed"
				(path ""
					(reference "#PWR0132")
					(unit 1)
				)
			)
		)
	)
	(symbol
		(lib_id "antmicropower:GND")
		(at 128.27 67.945 0)
		(unit 1)
		(exclude_from_sim no)
		(in_bom yes)
		(on_board yes)
		(dnp no)
		(property "Reference" "#PWR0137"
			(at 128.27 74.295 0)
			(effects
				(font
					(size 1.27 1.27)
				)
				(hide yes)
			)
		)
		(property "Value" "GND"
			(at 128.397 72.3392 0)
			(effects
				(font
					(size 1.27 1.27)
				)
			)
		)
		(property "Footprint" ""
			(at 128.27 67.945 0)
			(effects
				(font
					(size 1.27 1.27)
				)
				(hide yes)
			)
		)
		(property "Datasheet" ""
			(at 128.27 67.945 0)
			(effects
				(font
					(size 1.27 1.27)
				)
				(hide yes)
			)
		)
		(property "Description" ""
			(at 128.27 67.945 0)
			(effects
				(font
					(size 1.27 1.27)
				)
			)
		)
		(pin "1"
		)
		(instances
			(project "lpddr4-testbed"
				(path ""
					(reference "#PWR0137")
					(unit 1)
				)
			)
		)
	)
	(symbol
		(lib_id "antmicropower:GND")
		(at 114.3 183.515 0)
		(unit 1)
		(exclude_from_sim no)
		(in_bom yes)
		(on_board yes)
		(dnp no)
		(property "Reference" "#PWR0134"
			(at 114.3 189.865 0)
			(effects
				(font
					(size 1.27 1.27)
				)
				(hide yes)
			)
		)
		(property "Value" "GND"
			(at 114.427 187.9092 0)
			(effects
				(font
					(size 1.27 1.27)
				)
			)
		)
		(property "Footprint" ""
			(at 114.3 183.515 0)
			(effects
				(font
					(size 1.27 1.27)
				)
				(hide yes)
			)
		)
		(property "Datasheet" ""
			(at 114.3 183.515 0)
			(effects
				(font
					(size 1.27 1.27)
				)
				(hide yes)
			)
		)
		(property "Description" ""
			(at 114.3 183.515 0)
			(effects
				(font
					(size 1.27 1.27)
				)
			)
		)
		(pin "1"
		)
		(instances
			(project "lpddr4-testbed"
				(path ""
					(reference "#PWR0134")
					(unit 1)
				)
			)
		)
	)
	(symbol
		(lib_id "antmicropower:GND")
		(at 121.285 52.705 0)
		(unit 1)
		(exclude_from_sim no)
		(in_bom yes)
		(on_board yes)
		(dnp no)
		(property "Reference" "#PWR0146"
			(at 121.285 59.055 0)
			(effects
				(font
					(size 1.27 1.27)
				)
				(hide yes)
			)
		)
		(property "Value" "GND"
			(at 121.412 57.0992 0)
			(effects
				(font
					(size 1.27 1.27)
				)
			)
		)
		(property "Footprint" ""
			(at 121.285 52.705 0)
			(effects
				(font
					(size 1.27 1.27)
				)
				(hide yes)
			)
		)
		(property "Datasheet" ""
			(at 121.285 52.705 0)
			(effects
				(font
					(size 1.27 1.27)
				)
				(hide yes)
			)
		)
		(property "Description" ""
			(at 121.285 52.705 0)
			(effects
				(font
					(size 1.27 1.27)
				)
			)
		)
		(pin "1"
		)
		(instances
			(project "lpddr4-testbed"
				(path ""
					(reference "#PWR0146")
					(unit 1)
				)
			)
		)
	)
	(symbol
		(lib_id "antmicropower:GND")
		(at 163.195 183.515 0)
		(unit 1)
		(exclude_from_sim no)
		(in_bom yes)
		(on_board yes)
		(dnp no)
		(property "Reference" "#PWR0120"
			(at 163.195 189.865 0)
			(effects
				(font
					(size 1.27 1.27)
				)
				(hide yes)
			)
		)
		(property "Value" "GND"
			(at 163.322 187.9092 0)
			(effects
				(font
					(size 1.27 1.27)
				)
			)
		)
		(property "Footprint" ""
			(at 163.195 183.515 0)
			(effects
				(font
					(size 1.27 1.27)
				)
				(hide yes)
			)
		)
		(property "Datasheet" ""
			(at 163.195 183.515 0)
			(effects
				(font
					(size 1.27 1.27)
				)
				(hide yes)
			)
		)
		(property "Description" ""
			(at 163.195 183.515 0)
			(effects
				(font
					(size 1.27 1.27)
				)
			)
		)
		(pin "1"
		)
		(instances
			(project "lpddr4-testbed"
				(path ""
					(reference "#PWR0120")
					(unit 1)
				)
			)
		)
	)
	(symbol
		(lib_id "antmicropower:GND")
		(at 128.27 52.705 0)
		(unit 1)
		(exclude_from_sim no)
		(in_bom yes)
		(on_board yes)
		(dnp no)
		(property "Reference" "#PWR0143"
			(at 128.27 59.055 0)
			(effects
				(font
					(size 1.27 1.27)
				)
				(hide yes)
			)
		)
		(property "Value" "GND"
			(at 128.397 57.0992 0)
			(effects
				(font
					(size 1.27 1.27)
				)
			)
		)
		(property "Footprint" ""
			(at 128.27 52.705 0)
			(effects
				(font
					(size 1.27 1.27)
				)
				(hide yes)
			)
		)
		(property "Datasheet" ""
			(at 128.27 52.705 0)
			(effects
				(font
					(size 1.27 1.27)
				)
				(hide yes)
			)
		)
		(property "Description" ""
			(at 128.27 52.705 0)
			(effects
				(font
					(size 1.27 1.27)
				)
			)
		)
		(pin "1"
		)
		(instances
			(project "lpddr4-testbed"
				(path ""
					(reference "#PWR0143")
					(unit 1)
				)
			)
		)
	)
	(symbol
		(lib_id "antmicropower:GND")
		(at 142.24 52.705 0)
		(unit 1)
		(exclude_from_sim no)
		(in_bom yes)
		(on_board yes)
		(dnp no)
		(property "Reference" "#PWR0145"
			(at 142.24 59.055 0)
			(effects
				(font
					(size 1.27 1.27)
				)
				(hide yes)
			)
		)
		(property "Value" "GND"
			(at 142.367 57.0992 0)
			(effects
				(font
					(size 1.27 1.27)
				)
			)
		)
		(property "Footprint" ""
			(at 142.24 52.705 0)
			(effects
				(font
					(size 1.27 1.27)
				)
				(hide yes)
			)
		)
		(property "Datasheet" ""
			(at 142.24 52.705 0)
			(effects
				(font
					(size 1.27 1.27)
				)
				(hide yes)
			)
		)
		(property "Description" ""
			(at 142.24 52.705 0)
			(effects
				(font
					(size 1.27 1.27)
				)
			)
		)
		(pin "1"
		)
		(instances
			(project "lpddr4-testbed"
				(path ""
					(reference "#PWR0145")
					(unit 1)
				)
			)
		)
	)
	(symbol
		(lib_id "antmicropower:GND")
		(at 163.195 83.185 0)
		(unit 1)
		(exclude_from_sim no)
		(in_bom yes)
		(on_board yes)
		(dnp no)
		(property "Reference" "#PWR0147"
			(at 163.195 89.535 0)
			(effects
				(font
					(size 1.27 1.27)
				)
				(hide yes)
			)
		)
		(property "Value" "GND"
			(at 163.322 87.5792 0)
			(effects
				(font
					(size 1.27 1.27)
				)
			)
		)
		(property "Footprint" ""
			(at 163.195 83.185 0)
			(effects
				(font
					(size 1.27 1.27)
				)
				(hide yes)
			)
		)
		(property "Datasheet" ""
			(at 163.195 83.185 0)
			(effects
				(font
					(size 1.27 1.27)
				)
				(hide yes)
			)
		)
		(property "Description" ""
			(at 163.195 83.185 0)
			(effects
				(font
					(size 1.27 1.27)
				)
			)
		)
		(pin "1"
		)
		(instances
			(project "lpddr4-testbed"
				(path ""
					(reference "#PWR0147")
					(unit 1)
				)
			)
		)
	)
	(symbol
		(lib_id "antmicropower:GND")
		(at 128.27 153.035 0)
		(unit 1)
		(exclude_from_sim no)
		(in_bom yes)
		(on_board yes)
		(dnp no)
		(property "Reference" "#PWR0123"
			(at 128.27 159.385 0)
			(effects
				(font
					(size 1.27 1.27)
				)
				(hide yes)
			)
		)
		(property "Value" "GND"
			(at 128.397 157.4292 0)
			(effects
				(font
					(size 1.27 1.27)
				)
			)
		)
		(property "Footprint" ""
			(at 128.27 153.035 0)
			(effects
				(font
					(size 1.27 1.27)
				)
				(hide yes)
			)
		)
		(property "Datasheet" ""
			(at 128.27 153.035 0)
			(effects
				(font
					(size 1.27 1.27)
				)
				(hide yes)
			)
		)
		(property "Description" ""
			(at 128.27 153.035 0)
			(effects
				(font
					(size 1.27 1.27)
				)
			)
		)
		(pin "1"
		)
		(instances
			(project "lpddr4-testbed"
				(path ""
					(reference "#PWR0123")
					(unit 1)
				)
			)
		)
	)
	(symbol
		(lib_id "antmicropower:GND")
		(at 156.21 83.185 0)
		(unit 1)
		(exclude_from_sim no)
		(in_bom yes)
		(on_board yes)
		(dnp no)
		(property "Reference" "#PWR0151"
			(at 156.21 89.535 0)
			(effects
				(font
					(size 1.27 1.27)
				)
				(hide yes)
			)
		)
		(property "Value" "GND"
			(at 156.337 87.5792 0)
			(effects
				(font
					(size 1.27 1.27)
				)
			)
		)
		(property "Footprint" ""
			(at 156.21 83.185 0)
			(effects
				(font
					(size 1.27 1.27)
				)
				(hide yes)
			)
		)
		(property "Datasheet" ""
			(at 156.21 83.185 0)
			(effects
				(font
					(size 1.27 1.27)
				)
				(hide yes)
			)
		)
		(property "Description" ""
			(at 156.21 83.185 0)
			(effects
				(font
					(size 1.27 1.27)
				)
			)
		)
		(pin "1"
		)
		(instances
			(project "lpddr4-testbed"
				(path ""
					(reference "#PWR0151")
					(unit 1)
				)
			)
		)
	)
	(symbol
		(lib_id "antmicropower:GND")
		(at 114.3 83.185 0)
		(unit 1)
		(exclude_from_sim no)
		(in_bom yes)
		(on_board yes)
		(dnp no)
		(property "Reference" "#PWR0138"
			(at 114.3 89.535 0)
			(effects
				(font
					(size 1.27 1.27)
				)
				(hide yes)
			)
		)
		(property "Value" "GND"
			(at 114.427 87.5792 0)
			(effects
				(font
					(size 1.27 1.27)
				)
			)
		)
		(property "Footprint" ""
			(at 114.3 83.185 0)
			(effects
				(font
					(size 1.27 1.27)
				)
				(hide yes)
			)
		)
		(property "Datasheet" ""
			(at 114.3 83.185 0)
			(effects
				(font
					(size 1.27 1.27)
				)
				(hide yes)
			)
		)
		(property "Description" ""
			(at 114.3 83.185 0)
			(effects
				(font
					(size 1.27 1.27)
				)
			)
		)
		(pin "1"
		)
		(instances
			(project "lpddr4-testbed"
				(path ""
					(reference "#PWR0138")
					(unit 1)
				)
			)
		)
	)
	(symbol
		(lib_id "antmicropower:GND")
		(at 156.21 153.035 0)
		(unit 1)
		(exclude_from_sim no)
		(in_bom yes)
		(on_board yes)
		(dnp no)
		(property "Reference" "#PWR0125"
			(at 156.21 159.385 0)
			(effects
				(font
					(size 1.27 1.27)
				)
				(hide yes)
			)
		)
		(property "Value" "GND"
			(at 156.337 157.4292 0)
			(effects
				(font
					(size 1.27 1.27)
				)
			)
		)
		(property "Footprint" ""
			(at 156.21 153.035 0)
			(effects
				(font
					(size 1.27 1.27)
				)
				(hide yes)
			)
		)
		(property "Datasheet" ""
			(at 156.21 153.035 0)
			(effects
				(font
					(size 1.27 1.27)
				)
				(hide yes)
			)
		)
		(property "Description" ""
			(at 156.21 153.035 0)
			(effects
				(font
					(size 1.27 1.27)
				)
			)
		)
		(pin "1"
		)
		(instances
			(project "lpddr4-testbed"
				(path ""
					(reference "#PWR0125")
					(unit 1)
				)
			)
		)
	)
	(symbol
		(lib_id "antmicropower:GND")
		(at 114.3 67.945 0)
		(unit 1)
		(exclude_from_sim no)
		(in_bom yes)
		(on_board yes)
		(dnp no)
		(property "Reference" "#PWR0140"
			(at 114.3 74.295 0)
			(effects
				(font
					(size 1.27 1.27)
				)
				(hide yes)
			)
		)
		(property "Value" "GND"
			(at 114.427 72.3392 0)
			(effects
				(font
					(size 1.27 1.27)
				)
			)
		)
		(property "Footprint" ""
			(at 114.3 67.945 0)
			(effects
				(font
					(size 1.27 1.27)
				)
				(hide yes)
			)
		)
		(property "Datasheet" ""
			(at 114.3 67.945 0)
			(effects
				(font
					(size 1.27 1.27)
				)
				(hide yes)
			)
		)
		(property "Description" ""
			(at 114.3 67.945 0)
			(effects
				(font
					(size 1.27 1.27)
				)
			)
		)
		(pin "1"
		)
		(instances
			(project "lpddr4-testbed"
				(path ""
					(reference "#PWR0140")
					(unit 1)
				)
			)
		)
	)
	(symbol
		(lib_id "antmicropower:GND")
		(at 156.21 52.705 0)
		(unit 1)
		(exclude_from_sim no)
		(in_bom yes)
		(on_board yes)
		(dnp no)
		(property "Reference" "#PWR0149"
			(at 156.21 59.055 0)
			(effects
				(font
					(size 1.27 1.27)
				)
				(hide yes)
			)
		)
		(property "Value" "GND"
			(at 156.337 57.0992 0)
			(effects
				(font
					(size 1.27 1.27)
				)
			)
		)
		(property "Footprint" ""
			(at 156.21 52.705 0)
			(effects
				(font
					(size 1.27 1.27)
				)
				(hide yes)
			)
		)
		(property "Datasheet" ""
			(at 156.21 52.705 0)
			(effects
				(font
					(size 1.27 1.27)
				)
				(hide yes)
			)
		)
		(property "Description" ""
			(at 156.21 52.705 0)
			(effects
				(font
					(size 1.27 1.27)
				)
			)
		)
		(pin "1"
		)
		(instances
			(project "lpddr4-testbed"
				(path ""
					(reference "#PWR0149")
					(unit 1)
				)
			)
		)
	)
	(symbol
		(lib_id "antmicropower:GND")
		(at 142.24 183.515 0)
		(unit 1)
		(exclude_from_sim no)
		(in_bom yes)
		(on_board yes)
		(dnp no)
		(property "Reference" "#PWR0131"
			(at 142.24 189.865 0)
			(effects
				(font
					(size 1.27 1.27)
				)
				(hide yes)
			)
		)
		(property "Value" "GND"
			(at 142.367 187.9092 0)
			(effects
				(font
					(size 1.27 1.27)
				)
			)
		)
		(property "Footprint" ""
			(at 142.24 183.515 0)
			(effects
				(font
					(size 1.27 1.27)
				)
				(hide yes)
			)
		)
		(property "Datasheet" ""
			(at 142.24 183.515 0)
			(effects
				(font
					(size 1.27 1.27)
				)
				(hide yes)
			)
		)
		(property "Description" ""
			(at 142.24 183.515 0)
			(effects
				(font
					(size 1.27 1.27)
				)
			)
		)
		(pin "1"
		)
		(instances
			(project "lpddr4-testbed"
				(path ""
					(reference "#PWR0131")
					(unit 1)
				)
			)
		)
	)
	(symbol
		(lib_id "antmicropower:GND")
		(at 135.255 153.035 0)
		(unit 1)
		(exclude_from_sim no)
		(in_bom yes)
		(on_board yes)
		(dnp no)
		(property "Reference" "#PWR0122"
			(at 135.255 159.385 0)
			(effects
				(font
					(size 1.27 1.27)
				)
				(hide yes)
			)
		)
		(property "Value" "GND"
			(at 135.382 157.4292 0)
			(effects
				(font
					(size 1.27 1.27)
				)
			)
		)
		(property "Footprint" ""
			(at 135.255 153.035 0)
			(effects
				(font
					(size 1.27 1.27)
				)
				(hide yes)
			)
		)
		(property "Datasheet" ""
			(at 135.255 153.035 0)
			(effects
				(font
					(size 1.27 1.27)
				)
				(hide yes)
			)
		)
		(property "Description" ""
			(at 135.255 153.035 0)
			(effects
				(font
					(size 1.27 1.27)
				)
			)
		)
		(pin "1"
		)
		(instances
			(project "lpddr4-testbed"
				(path ""
					(reference "#PWR0122")
					(unit 1)
				)
			)
		)
	)
	(symbol
		(lib_id "antmicropower:GND")
		(at 121.285 168.275 0)
		(unit 1)
		(exclude_from_sim no)
		(in_bom yes)
		(on_board yes)
		(dnp no)
		(property "Reference" "#PWR0127"
			(at 121.285 174.625 0)
			(effects
				(font
					(size 1.27 1.27)
				)
				(hide yes)
			)
		)
		(property "Value" "GND"
			(at 121.412 172.6692 0)
			(effects
				(font
					(size 1.27 1.27)
				)
			)
		)
		(property "Footprint" ""
			(at 121.285 168.275 0)
			(effects
				(font
					(size 1.27 1.27)
				)
				(hide yes)
			)
		)
		(property "Datasheet" ""
			(at 121.285 168.275 0)
			(effects
				(font
					(size 1.27 1.27)
				)
				(hide yes)
			)
		)
		(property "Description" ""
			(at 121.285 168.275 0)
			(effects
				(font
					(size 1.27 1.27)
				)
			)
		)
		(pin "1"
		)
		(instances
			(project "lpddr4-testbed"
				(path ""
					(reference "#PWR0127")
					(unit 1)
				)
			)
		)
	)
	(symbol
		(lib_id "antmicropower:GND")
		(at 121.285 67.945 0)
		(unit 1)
		(exclude_from_sim no)
		(in_bom yes)
		(on_board yes)
		(dnp no)
		(property "Reference" "#PWR0139"
			(at 121.285 74.295 0)
			(effects
				(font
					(size 1.27 1.27)
				)
				(hide yes)
			)
		)
		(property "Value" "GND"
			(at 121.412 72.3392 0)
			(effects
				(font
					(size 1.27 1.27)
				)
			)
		)
		(property "Footprint" ""
			(at 121.285 67.945 0)
			(effects
				(font
					(size 1.27 1.27)
				)
				(hide yes)
			)
		)
		(property "Datasheet" ""
			(at 121.285 67.945 0)
			(effects
				(font
					(size 1.27 1.27)
				)
				(hide yes)
			)
		)
		(property "Description" ""
			(at 121.285 67.945 0)
			(effects
				(font
					(size 1.27 1.27)
				)
			)
		)
		(pin "1"
		)
		(instances
			(project "lpddr4-testbed"
				(path ""
					(reference "#PWR0139")
					(unit 1)
				)
			)
		)
	)
	(symbol
		(lib_id "antmicropower:GND")
		(at 135.255 52.705 0)
		(unit 1)
		(exclude_from_sim no)
		(in_bom yes)
		(on_board yes)
		(dnp no)
		(property "Reference" "#PWR0144"
			(at 135.255 59.055 0)
			(effects
				(font
					(size 1.27 1.27)
				)
				(hide yes)
			)
		)
		(property "Value" "GND"
			(at 135.382 57.0992 0)
			(effects
				(font
					(size 1.27 1.27)
				)
			)
		)
		(property "Footprint" ""
			(at 135.255 52.705 0)
			(effects
				(font
					(size 1.27 1.27)
				)
				(hide yes)
			)
		)
		(property "Datasheet" ""
			(at 135.255 52.705 0)
			(effects
				(font
					(size 1.27 1.27)
				)
				(hide yes)
			)
		)
		(property "Description" ""
			(at 135.255 52.705 0)
			(effects
				(font
					(size 1.27 1.27)
				)
			)
		)
		(pin "1"
		)
		(instances
			(project "lpddr4-testbed"
				(path ""
					(reference "#PWR0144")
					(unit 1)
				)
			)
		)
	)
	(symbol
		(lib_id "antmicropower:GND")
		(at 114.3 168.275 0)
		(unit 1)
		(exclude_from_sim no)
		(in_bom yes)
		(on_board yes)
		(dnp no)
		(property "Reference" "#PWR0133"
			(at 114.3 174.625 0)
			(effects
				(font
					(size 1.27 1.27)
				)
				(hide yes)
			)
		)
		(property "Value" "GND"
			(at 114.427 172.6692 0)
			(effects
				(font
					(size 1.27 1.27)
				)
			)
		)
		(property "Footprint" ""
			(at 114.3 168.275 0)
			(effects
				(font
					(size 1.27 1.27)
				)
				(hide yes)
			)
		)
		(property "Datasheet" ""
			(at 114.3 168.275 0)
			(effects
				(font
					(size 1.27 1.27)
				)
				(hide yes)
			)
		)
		(property "Description" ""
			(at 114.3 168.275 0)
			(effects
				(font
					(size 1.27 1.27)
				)
			)
		)
		(pin "1"
		)
		(instances
			(project "lpddr4-testbed"
				(path ""
					(reference "#PWR0133")
					(unit 1)
				)
			)
		)
	)
	(symbol
		(lib_id "antmicropower:GND")
		(at 149.225 83.185 0)
		(unit 1)
		(exclude_from_sim no)
		(in_bom yes)
		(on_board yes)
		(dnp no)
		(property "Reference" "#PWR0150"
			(at 149.225 89.535 0)
			(effects
				(font
					(size 1.27 1.27)
				)
				(hide yes)
			)
		)
		(property "Value" "GND"
			(at 149.352 87.5792 0)
			(effects
				(font
					(size 1.27 1.27)
				)
			)
		)
		(property "Footprint" ""
			(at 149.225 83.185 0)
			(effects
				(font
					(size 1.27 1.27)
				)
				(hide yes)
			)
		)
		(property "Datasheet" ""
			(at 149.225 83.185 0)
			(effects
				(font
					(size 1.27 1.27)
				)
				(hide yes)
			)
		)
		(property "Description" ""
			(at 149.225 83.185 0)
			(effects
				(font
					(size 1.27 1.27)
				)
			)
		)
		(pin "1"
		)
		(instances
			(project "lpddr4-testbed"
				(path ""
					(reference "#PWR0150")
					(unit 1)
				)
			)
		)
	)
	(symbol
		(lib_id "antmicropower:GND")
		(at 121.285 183.515 0)
		(unit 1)
		(exclude_from_sim no)
		(in_bom yes)
		(on_board yes)
		(dnp no)
		(property "Reference" "#PWR0129"
			(at 121.285 189.865 0)
			(effects
				(font
					(size 1.27 1.27)
				)
				(hide yes)
			)
		)
		(property "Value" "GND"
			(at 121.412 187.9092 0)
			(effects
				(font
					(size 1.27 1.27)
				)
			)
		)
		(property "Footprint" ""
			(at 121.285 183.515 0)
			(effects
				(font
					(size 1.27 1.27)
				)
				(hide yes)
			)
		)
		(property "Datasheet" ""
			(at 121.285 183.515 0)
			(effects
				(font
					(size 1.27 1.27)
				)
				(hide yes)
			)
		)
		(property "Description" ""
			(at 121.285 183.515 0)
			(effects
				(font
					(size 1.27 1.27)
				)
			)
		)
		(pin "1"
		)
		(instances
			(project "lpddr4-testbed"
				(path ""
					(reference "#PWR0129")
					(unit 1)
				)
			)
		)
	)
	(symbol
		(lib_id "antmicropower:GND")
		(at 135.255 83.185 0)
		(unit 1)
		(exclude_from_sim no)
		(in_bom yes)
		(on_board yes)
		(dnp no)
		(property "Reference" "#PWR0136"
			(at 135.255 89.535 0)
			(effects
				(font
					(size 1.27 1.27)
				)
				(hide yes)
			)
		)
		(property "Value" "GND"
			(at 135.382 87.5792 0)
			(effects
				(font
					(size 1.27 1.27)
				)
			)
		)
		(property "Footprint" ""
			(at 135.255 83.185 0)
			(effects
				(font
					(size 1.27 1.27)
				)
				(hide yes)
			)
		)
		(property "Datasheet" ""
			(at 135.255 83.185 0)
			(effects
				(font
					(size 1.27 1.27)
				)
				(hide yes)
			)
		)
		(property "Description" ""
			(at 135.255 83.185 0)
			(effects
				(font
					(size 1.27 1.27)
				)
			)
		)
		(pin "1"
		)
		(instances
			(project "lpddr4-testbed"
				(path ""
					(reference "#PWR0136")
					(unit 1)
				)
			)
		)
	)
	(symbol
		(lib_id "antmicropower:GND")
		(at 149.225 183.515 0)
		(unit 1)
		(exclude_from_sim no)
		(in_bom yes)
		(on_board yes)
		(dnp no)
		(property "Reference" "#PWR0118"
			(at 149.225 189.865 0)
			(effects
				(font
					(size 1.27 1.27)
				)
				(hide yes)
			)
		)
		(property "Value" "GND"
			(at 149.352 187.9092 0)
			(effects
				(font
					(size 1.27 1.27)
				)
			)
		)
		(property "Footprint" ""
			(at 149.225 183.515 0)
			(effects
				(font
					(size 1.27 1.27)
				)
				(hide yes)
			)
		)
		(property "Datasheet" ""
			(at 149.225 183.515 0)
			(effects
				(font
					(size 1.27 1.27)
				)
				(hide yes)
			)
		)
		(property "Description" ""
			(at 149.225 183.515 0)
			(effects
				(font
					(size 1.27 1.27)
				)
			)
		)
		(pin "1"
		)
		(instances
			(project "lpddr4-testbed"
				(path ""
					(reference "#PWR0118")
					(unit 1)
				)
			)
		)
	)
	(symbol
		(lib_id "antmicropower:GND")
		(at 149.225 52.705 0)
		(unit 1)
		(exclude_from_sim no)
		(in_bom yes)
		(on_board yes)
		(dnp no)
		(property "Reference" "#PWR0148"
			(at 149.225 59.055 0)
			(effects
				(font
					(size 1.27 1.27)
				)
				(hide yes)
			)
		)
		(property "Value" "GND"
			(at 149.352 57.0992 0)
			(effects
				(font
					(size 1.27 1.27)
				)
			)
		)
		(property "Footprint" ""
			(at 149.225 52.705 0)
			(effects
				(font
					(size 1.27 1.27)
				)
				(hide yes)
			)
		)
		(property "Datasheet" ""
			(at 149.225 52.705 0)
			(effects
				(font
					(size 1.27 1.27)
				)
				(hide yes)
			)
		)
		(property "Description" ""
			(at 149.225 52.705 0)
			(effects
				(font
					(size 1.27 1.27)
				)
			)
		)
		(pin "1"
		)
		(instances
			(project "lpddr4-testbed"
				(path ""
					(reference "#PWR0148")
					(unit 1)
				)
			)
		)
	)
	(symbol
		(lib_id "antmicropower:GND")
		(at 149.225 153.035 0)
		(unit 1)
		(exclude_from_sim no)
		(in_bom yes)
		(on_board yes)
		(dnp no)
		(property "Reference" "#PWR0126"
			(at 149.225 159.385 0)
			(effects
				(font
					(size 1.27 1.27)
				)
				(hide yes)
			)
		)
		(property "Value" "GND"
			(at 149.352 157.4292 0)
			(effects
				(font
					(size 1.27 1.27)
				)
			)
		)
		(property "Footprint" ""
			(at 149.225 153.035 0)
			(effects
				(font
					(size 1.27 1.27)
				)
				(hide yes)
			)
		)
		(property "Datasheet" ""
			(at 149.225 153.035 0)
			(effects
				(font
					(size 1.27 1.27)
				)
				(hide yes)
			)
		)
		(property "Description" ""
			(at 149.225 153.035 0)
			(effects
				(font
					(size 1.27 1.27)
				)
			)
		)
		(pin "1"
		)
		(instances
			(project "lpddr4-testbed"
				(path ""
					(reference "#PWR0126")
					(unit 1)
				)
			)
		)
	)
	(symbol
		(lib_id "antmicropower:GND")
		(at 128.27 183.515 0)
		(unit 1)
		(exclude_from_sim no)
		(in_bom yes)
		(on_board yes)
		(dnp no)
		(property "Reference" "#PWR0128"
			(at 128.27 189.865 0)
			(effects
				(font
					(size 1.27 1.27)
				)
				(hide yes)
			)
		)
		(property "Value" "GND"
			(at 128.397 187.9092 0)
			(effects
				(font
					(size 1.27 1.27)
				)
			)
		)
		(property "Footprint" ""
			(at 128.27 183.515 0)
			(effects
				(font
					(size 1.27 1.27)
				)
				(hide yes)
			)
		)
		(property "Datasheet" ""
			(at 128.27 183.515 0)
			(effects
				(font
					(size 1.27 1.27)
				)
				(hide yes)
			)
		)
		(property "Description" ""
			(at 128.27 183.515 0)
			(effects
				(font
					(size 1.27 1.27)
				)
			)
		)
		(pin "1"
		)
		(instances
			(project "lpddr4-testbed"
				(path ""
					(reference "#PWR0128")
					(unit 1)
				)
			)
		)
	)
	(symbol
		(lib_id "antmicropower:GND")
		(at 135.255 183.515 0)
		(unit 1)
		(exclude_from_sim no)
		(in_bom yes)
		(on_board yes)
		(dnp no)
		(property "Reference" "#PWR0130"
			(at 135.255 189.865 0)
			(effects
				(font
					(size 1.27 1.27)
				)
				(hide yes)
			)
		)
		(property "Value" "GND"
			(at 135.382 187.9092 0)
			(effects
				(font
					(size 1.27 1.27)
				)
			)
		)
		(property "Footprint" ""
			(at 135.255 183.515 0)
			(effects
				(font
					(size 1.27 1.27)
				)
				(hide yes)
			)
		)
		(property "Datasheet" ""
			(at 135.255 183.515 0)
			(effects
				(font
					(size 1.27 1.27)
				)
				(hide yes)
			)
		)
		(property "Description" ""
			(at 135.255 183.515 0)
			(effects
				(font
					(size 1.27 1.27)
				)
			)
		)
		(pin "1"
		)
		(instances
			(project "lpddr4-testbed"
				(path ""
					(reference "#PWR0130")
					(unit 1)
				)
			)
		)
	)
	(symbol
		(lib_id "antmicropower:GND")
		(at 156.21 183.515 0)
		(unit 1)
		(exclude_from_sim no)
		(in_bom yes)
		(on_board yes)
		(dnp no)
		(property "Reference" "#PWR0119"
			(at 156.21 189.865 0)
			(effects
				(font
					(size 1.27 1.27)
				)
				(hide yes)
			)
		)
		(property "Value" "GND"
			(at 156.337 187.9092 0)
			(effects
				(font
					(size 1.27 1.27)
				)
			)
		)
		(property "Footprint" ""
			(at 156.21 183.515 0)
			(effects
				(font
					(size 1.27 1.27)
				)
				(hide yes)
			)
		)
		(property "Datasheet" ""
			(at 156.21 183.515 0)
			(effects
				(font
					(size 1.27 1.27)
				)
				(hide yes)
			)
		)
		(property "Description" ""
			(at 156.21 183.515 0)
			(effects
				(font
					(size 1.27 1.27)
				)
			)
		)
		(pin "1"
		)
		(instances
			(project "lpddr4-testbed"
				(path ""
					(reference "#PWR0119")
					(unit 1)
				)
			)
		)
	)
	(symbol
		(lib_id "antmicropower:GND")
		(at 121.285 153.035 0)
		(unit 1)
		(exclude_from_sim no)
		(in_bom yes)
		(on_board yes)
		(dnp no)
		(property "Reference" "#PWR0124"
			(at 121.285 159.385 0)
			(effects
				(font
					(size 1.27 1.27)
				)
				(hide yes)
			)
		)
		(property "Value" "GND"
			(at 121.412 157.4292 0)
			(effects
				(font
					(size 1.27 1.27)
				)
			)
		)
		(property "Footprint" ""
			(at 121.285 153.035 0)
			(effects
				(font
					(size 1.27 1.27)
				)
				(hide yes)
			)
		)
		(property "Datasheet" ""
			(at 121.285 153.035 0)
			(effects
				(font
					(size 1.27 1.27)
				)
				(hide yes)
			)
		)
		(property "Description" ""
			(at 121.285 153.035 0)
			(effects
				(font
					(size 1.27 1.27)
				)
			)
		)
		(pin "1"
		)
		(instances
			(project "lpddr4-testbed"
				(path ""
					(reference "#PWR0124")
					(unit 1)
				)
			)
		)
	)
	(symbol
		(lib_id "antmicropower:GND")
		(at 142.24 153.035 0)
		(unit 1)
		(exclude_from_sim no)
		(in_bom yes)
		(on_board yes)
		(dnp no)
		(property "Reference" "#PWR0121"
			(at 142.24 159.385 0)
			(effects
				(font
					(size 1.27 1.27)
				)
				(hide yes)
			)
		)
		(property "Value" "GND"
			(at 142.367 157.4292 0)
			(effects
				(font
					(size 1.27 1.27)
				)
			)
		)
		(property "Footprint" ""
			(at 142.24 153.035 0)
			(effects
				(font
					(size 1.27 1.27)
				)
				(hide yes)
			)
		)
		(property "Datasheet" ""
			(at 142.24 153.035 0)
			(effects
				(font
					(size 1.27 1.27)
				)
				(hide yes)
			)
		)
		(property "Description" ""
			(at 142.24 153.035 0)
			(effects
				(font
					(size 1.27 1.27)
				)
			)
		)
		(pin "1"
		)
		(instances
			(project "lpddr4-testbed"
				(path ""
					(reference "#PWR0121")
					(unit 1)
				)
			)
		)
	)
	(symbol
		(lib_id "antmicropower:GND")
		(at 121.285 83.185 0)
		(unit 1)
		(exclude_from_sim no)
		(in_bom yes)
		(on_board yes)
		(dnp no)
		(property "Reference" "#PWR0141"
			(at 121.285 89.535 0)
			(effects
				(font
					(size 1.27 1.27)
				)
				(hide yes)
			)
		)
		(property "Value" "GND"
			(at 121.412 87.5792 0)
			(effects
				(font
					(size 1.27 1.27)
				)
			)
		)
		(property "Footprint" ""
			(at 121.285 83.185 0)
			(effects
				(font
					(size 1.27 1.27)
				)
				(hide yes)
			)
		)
		(property "Datasheet" ""
			(at 121.285 83.185 0)
			(effects
				(font
					(size 1.27 1.27)
				)
				(hide yes)
			)
		)
		(property "Description" ""
			(at 121.285 83.185 0)
			(effects
				(font
					(size 1.27 1.27)
				)
			)
		)
		(pin "1"
		)
		(instances
			(project "lpddr4-testbed"
				(path ""
					(reference "#PWR0141")
					(unit 1)
				)
			)
		)
	)
	(symbol
		(lib_id "antmicropower:GND")
		(at 142.24 83.185 0)
		(unit 1)
		(exclude_from_sim no)
		(in_bom yes)
		(on_board yes)
		(dnp no)
		(property "Reference" "#PWR0135"
			(at 142.24 89.535 0)
			(effects
				(font
					(size 1.27 1.27)
				)
				(hide yes)
			)
		)
		(property "Value" "GND"
			(at 142.367 87.5792 0)
			(effects
				(font
					(size 1.27 1.27)
				)
			)
		)
		(property "Footprint" ""
			(at 142.24 83.185 0)
			(effects
				(font
					(size 1.27 1.27)
				)
				(hide yes)
			)
		)
		(property "Datasheet" ""
			(at 142.24 83.185 0)
			(effects
				(font
					(size 1.27 1.27)
				)
				(hide yes)
			)
		)
		(property "Description" ""
			(at 142.24 83.185 0)
			(effects
				(font
					(size 1.27 1.27)
				)
			)
		)
		(pin "1"
		)
		(instances
			(project "lpddr4-testbed"
				(path ""
					(reference "#PWR0135")
					(unit 1)
				)
			)
		)
	)
)
